# Altium SchDoc records: 06-MAC.SchDoc
|HEADER=Protel for Windows - Schematic Capture Binary File Version 5.0|Weight=1004|MinorVersion=6
|RECORD=31|FontIdCount=8|Size1=10|FontName1=Times New Roman|Size2=8|FontName2=Arial|Size3=10|FontName3=Arial|Size4=12|Underline4=T|FontName4=Arial|Size5=11|FontName5=Arial|Size6=24|FontName6=Times New Roman|Size7=10|Underline7=T|FontName7=Times New Roman|Size8=12|FontName8=Arial|UseMBCS=T|IsBOC=T|HotSpotGridOn=T|HotSpotGridSize_Frac=50000|SheetStyle=12|SystemFont=3|BorderOn=T|SheetNumberSpaceSize=12|AreaColor=16317695|SnapGridOn=T|SnapGridSize=10|VisibleGridOn=T|VisibleGridSize=10|CustomX=2338|CustomX_Frac=58268|CustomY=1653|CustomY_Frac=54331|CustomXZones=8|CustomYZones=6|CustomMarginWidth=19|CustomMarginWidth_Frac=80000|ShowTemplateGraphics=T|TemplateFileName=C:\Users\<user>\Documents\Altium\AD20\Templates\Timecard.SchDot|Display_Unit=0
|RECORD=39|IsNotAccesible=T|OwnerPartId=-1|FileName=C:\Users\<user>\Documents\Altium\AD20\Templates\Timecard.SchDot
|RECORD=4|OwnerIndex=1|OwnerPartId=-1|Location.X=1594|Location.Y=39|Color=8388608|FontID=4|Text=timingcard.com|URL=http://timingcard.com
|RECORD=6|OwnerIndex=1|IndexInSheet=1|OwnerPartId=-1|LocationCount=2|X1=1680|Y1=35|X2=1576|Y2=35
|RECORD=4|OwnerIndex=1|IndexInSheet=2|OwnerPartId=-1|Location.X=1615|Location.Y=27|Justification=4|Color=16711680|FontID=5|Text==SheetNumber
|RECORD=4|OwnerIndex=1|IndexInSheet=3|OwnerPartId=-1|Location.X=1581|Location.X_Frac=42446|Location.Y=29|Location.Y_Frac=96838|Justification=3|FontID=2|Text=SHEET
|RECORD=4|OwnerIndex=1|IndexInSheet=4|OwnerPartId=-1|Location.X=1639|Location.X_Frac=42446|Location.Y=29|Location.Y_Frac=96838|Justification=3|FontID=2|Text=OF
|RECORD=6|OwnerIndex=1|IndexInSheet=5|OwnerPartId=-1|LineWidth=1|LocationCount=2|X1=1679|X1_Frac=42446|Y1=117|Y1_Frac=96838|X2=1576|Y2=118
|RECORD=4|OwnerIndex=1|IndexInSheet=6|OwnerPartId=-1|Location.X=1659|Location.Y=27|Justification=4|Color=16711680|FontID=5|Text==SheetTotal
|RECORD=30|OwnerIndex=1|IndexInSheet=7|OwnerPartId=-1|Location.X=1578|Location.Y=65|Corner.X=1673|Corner.X_Frac=88801|Corner.Y=115|KeepAspect=T|FileName=C:\Users\<user>\Desktop\Timecard Logo\TIMECARD.jpg
|RECORD=6|OwnerIndex=1|IndexInSheet=8|OwnerPartId=-1|LineWidth=1|LocationCount=2|X1=1576|X1_Frac=3162|Y1=117|Y1_Frac=42446|X2=1576|Y2=21
|RECORD=6|OwnerIndex=1|IndexInSheet=9|OwnerPartId=-1|LocationCount=2|X1=1680|Y1=51|X2=1576|Y2=51
|RECORD=4|OwnerIndex=1|IndexInSheet=10|OwnerPartId=-1|Location.X=1581|Location.X_Frac=42446|Location.Y=56|Location.Y_Frac=96838|Justification=3|FontID=2|Text=REV
|RECORD=4|OwnerIndex=1|IndexInSheet=11|OwnerPartId=-1|Location.X=1619|Location.Y=57|Justification=3|FontID=2|Text=DATE
|RECORD=6|OwnerIndex=1|IndexInSheet=12|OwnerPartId=-1|LocationCount=2|X1=1680|Y1=65|X2=1576|Y2=65
|RECORD=4|OwnerIndex=1|IndexInSheet=13|OwnerPartId=-1|Location.X=1605|Location.Y=58|Justification=4|Color=16711680|FontID=5|Text==ProjectRevision
|RECORD=4|OwnerIndex=1|IndexInSheet=14|OwnerPartId=-1|Location.X=1659|Location.Y=58|Justification=4|Color=16711680|FontID=5|Text==ProjectDate
|RECORD=41|IndexInSheet=1|OwnerPartId=-1|Location.X=21474|Location.X_Frac=83647|Location.Y=21464|Location.Y_Frac=83647|Color=8388608|FontID=1|IsHidden=T|Text=01910|Name=Customer
|RECORD=41|IndexInSheet=2|OwnerPartId=-1|Location.X=1000|Location.Y=10|Color=8388608|FontID=1|IsHidden=T|Text=*|Name=DocStatus
|RECORD=17|IndexInSheet=3|OwnerPartId=-1|ShowNetName=T|Location.X=918|Location.Y=937|Color=255|FontID=1|Text=MAC_TX|IsCrossSheetConnector=T
|RECORD=17|IndexInSheet=4|OwnerPartId=-1|ShowNetName=T|Location.X=918|Location.Y=927|Color=255|FontID=1|Text=MAC_RX|IsCrossSheetConnector=T
|RECORD=17|IndexInSheet=5|OwnerPartId=-1|ShowNetName=T|Location.X=918|Location.Y=917|Color=255|FontID=1|Text=MAC_BITE|IsCrossSheetConnector=T
|RECORD=17|IndexInSheet=6|OwnerPartId=-1|ShowNetName=T|Location.X=618|Location.Y=917|Orientation=2|Color=255|FontID=1|Text=MAC_RF_OUT|IsCrossSheetConnector=T
|RECORD=17|IndexInSheet=7|OwnerPartId=-1|ShowNetName=T|Location.X=618|Location.Y=937|Orientation=2|Color=255|FontID=1|Text=MAC_FREQ_CTRL|IsCrossSheetConnector=T
|RECORD=22|IndexInSheet=8|OwnerPartId=-1|Location.X=610|Location.Y=610|Color=255|Orientation=1|Symbol=Thin Cross|IsActive=T|SuppressAll=T
|RECORD=22|IndexInSheet=9|OwnerPartId=-1|Location.X=610|Location.Y=600|Color=255|Orientation=1|Symbol=Thin Cross|IsActive=T|SuppressAll=T
|RECORD=22|IndexInSheet=10|OwnerPartId=-1|Location.X=610|Location.Y=590|Color=255|Orientation=1|Symbol=Thin Cross|IsActive=T|SuppressAll=T
|RECORD=22|IndexInSheet=11|OwnerPartId=-1|Location.X=610|Location.Y=580|Color=255|Orientation=1|Symbol=Thin Cross|IsActive=T|SuppressAll=T
|RECORD=22|IndexInSheet=12|OwnerPartId=-1|Location.X=610|Location.Y=570|Color=255|Orientation=1|Symbol=Thin Cross|IsActive=T|SuppressAll=T
|RECORD=22|IndexInSheet=13|OwnerPartId=-1|Location.X=610|Location.Y=560|Color=255|Orientation=1|Symbol=Thin Cross|IsActive=T|SuppressAll=T
|RECORD=22|IndexInSheet=14|OwnerPartId=-1|Location.X=610|Location.Y=550|Color=255|Orientation=1|Symbol=Thin Cross|IsActive=T|SuppressAll=T
|RECORD=17|IndexInSheet=15|OwnerPartId=-1|ShowNetName=T|Location.X=970|Location.Y=260|Orientation=2|Color=255|FontID=1|Text=FPGA_MAC_PPS_DIFF_IN0|IsCrossSheetConnector=T
|RECORD=17|IndexInSheet=16|OwnerPartId=-1|ShowNetName=T|Location.X=1040|Location.Y=660|Color=255|FontID=1|Text=MAC_USB+|IsCrossSheetConnector=T
|RECORD=17|IndexInSheet=17|OwnerPartId=-1|ShowNetName=T|Location.X=1040|Location.Y=650|Color=255|FontID=1|Text=MAC_USB-|IsCrossSheetConnector=T
|RECORD=17|IndexInSheet=18|OwnerPartId=-1|ShowNetName=T|Location.X=1040|Location.Y=640|Color=255|FontID=1|Text=MAC_USB_PWR|IsCrossSheetConnector=T
|RECORD=17|IndexInSheet=19|OwnerPartId=-1|ShowNetName=T|Location.X=190|Location.Y=310|Orientation=2|Color=255|FontID=1|Text=MAC_PPS_OUT+|IsCrossSheetConnector=T
|RECORD=17|IndexInSheet=20|OwnerPartId=-1|ShowNetName=T|Location.X=190|Location.Y=250|Orientation=2|Color=255|FontID=1|Text=MAC_PPS_OUT-|IsCrossSheetConnector=T
|RECORD=17|IndexInSheet=21|OwnerPartId=-1|ShowNetName=T|Location.X=1040|Location.Y=590|Color=255|FontID=1|Text=MAC_ALARM|IsCrossSheetConnector=T
|RECORD=17|IndexInSheet=22|OwnerPartId=-1|Style=4|ShowNetName=T|Location.X=810|Location.Y=530|Orientation=3|Color=128|FontID=1|Text=GND
|RECORD=17|IndexInSheet=23|OwnerPartId=-1|Style=4|ShowNetName=T|Location.X=640|Location.Y=810|Orientation=3|Color=128|FontID=1|Text=GND
|RECORD=17|IndexInSheet=24|OwnerPartId=-1|Style=4|ShowNetName=T|Location.X=1240|Location.Y=856|Orientation=3|Color=128|FontID=1|Text=GND
|RECORD=4|IndexInSheet=25|OwnerPartId=-1|Location.X=748|Location.Y=987|Color=8388608|FontID=6|Text=MAC
|RECORD=1|LibReference=CAP_0805_10UF_25V|ComponentDescription=CAP, CER, 10.UF, 25V, 10%, X5R, 0805|PartCount=2|DisplayModeCount=1|IndexInSheet=26|OwnerPartId=-1|Location.X=1161|Location.Y=846|CurrentPartId=1|LibraryPath=*|SourceLibraryName=Capacitors.IntLib|TargetFileName=*|AreaColor=11599871|Color=128|PartIDLocked=F|DesignItemId=CAP_0805_10UF_25V|AllPinCount=2
|RECORD=41|OwnerIndex=42|OwnerPartId=-1|Location.X=1161|Location.Y=846|Color=8388608|FontID=8|IsHidden=T|Text=TAIYO YUDEN|Name=MFG NAME
|RECORD=41|OwnerIndex=42|IndexInSheet=1|OwnerPartId=-1|Location.X=1161|Location.Y=846|Color=8388608|FontID=8|IsHidden=T|Text=TMK212BBJ106KG-T|Name=MFG PART NUM
|RECORD=41|OwnerIndex=42|IndexInSheet=2|OwnerPartId=-1|Location.X=1161|Location.Y=846|Color=8388608|FontID=8|IsHidden=T|Text=10/23/2013|Name=MODIFY DATE
|RECORD=41|OwnerIndex=42|IndexInSheet=3|OwnerPartId=-1|Location.X=1161|Location.Y=846|Color=8388608|FontID=8|IsHidden=T|Text=CAP, CER|Name=CATEGORY
|RECORD=41|OwnerIndex=42|IndexInSheet=4|OwnerPartId=-1|Location.X=1159|Location.Y=858|Location.Y_Frac=50000|Color=8388608|FontID=8|IsHidden=T|Text=4/11/2006 3:37:28 PM|Name=Date
|RECORD=41|OwnerIndex=42|IndexInSheet=5|OwnerPartId=-1|Location.X=1167|Location.Y=920|Location.Y_Frac=48252|Color=8388608|FontID=8|IsHidden=T|Text=*|Name=SHEETPART
|RECORD=41|OwnerIndex=42|IndexInSheet=6|OwnerPartId=-1|Location.X=1167|Location.Y=920|Location.Y_Frac=48252|Color=8388608|FontID=8|IsHidden=T|Text=10%|Name=P1
|RECORD=41|OwnerIndex=42|IndexInSheet=7|OwnerPartId=-1|Location.X=1167|Location.Y=920|Location.Y_Frac=48252|Color=8388608|FontID=8|IsHidden=T|Text=85C|Name=MAXTEMP
|RECORD=41|OwnerIndex=42|IndexInSheet=8|OwnerPartId=-1|Location.X=1167|Location.Y=920|Location.Y_Frac=48252|Color=8388608|FontID=8|IsHidden=T|Text=-55C|Name=MINTEMP
|RECORD=41|OwnerIndex=42|IndexInSheet=9|OwnerPartId=-1|Location.X=1167|Location.Y=920|Location.Y_Frac=48252|Color=8388608|FontID=8|IsHidden=T|Name=OTHER
|RECORD=41|OwnerIndex=42|IndexInSheet=10|OwnerPartId=-1|Location.X=1167|Location.Y=920|Location.Y_Frac=48252|Color=8388608|FontID=8|IsHidden=T|Text=25V|Name=P2
|RECORD=41|OwnerIndex=42|IndexInSheet=11|OwnerPartId=-1|Location.X=1167|Location.Y=920|Location.Y_Frac=48252|Color=8388608|FontID=8|IsHidden=T|Text=X5R|Name=P3
|RECORD=41|OwnerIndex=42|IndexInSheet=12|OwnerPartId=-1|Location.X=1167|Location.Y=920|Location.Y_Frac=48252|Color=8388608|FontID=8|IsHidden=T|Text=0805|Name=Size
|RECORD=41|OwnerIndex=42|IndexInSheet=13|OwnerPartId=-1|Location.X=1167|Location.Y=920|Location.Y_Frac=48252|Color=8388608|FontID=8|IsHidden=T|Name=SUB
|RECORD=41|OwnerIndex=42|IndexInSheet=14|OwnerPartId=-1|Location.X=1167|Location.Y=920|Location.Y_Frac=48252|Color=8388608|FontID=1|IsHidden=T|Text=CAP, CER, 10.UF, 10V, 10%, X5R, 0805|Name=DESC
|RECORD=41|OwnerIndex=42|IndexInSheet=15|OwnerPartId=-1|Location.X=1167|Location.Y=919|Location.Y_Frac=98252|Color=8388608|FontID=1|IsHidden=T|Text=MOUSER|Name=Supplier 1|ReadOnlyState=1
|RECORD=41|OwnerIndex=42|IndexInSheet=16|OwnerPartId=-1|Location.X=1167|Location.Y=919|Location.Y_Frac=98252|Color=8388608|FontID=1|IsHidden=T|Text=963-TMK212BBJ106KG-T|Name=Supplier Part Number 1|ReadOnlyState=1
|RECORD=41|OwnerIndex=42|IndexInSheet=17|OwnerPartId=-1|Location.X=1191|Location.Y=876|Color=8388608|FontID=8|Text=10uF|Name=VALUE
|RECORD=2|OwnerIndex=42|OwnerPartId=1|FormalType=1|Electrical=4|PinConglomerate=35|PinLength=10|Location.X=1181|Location.Y=876|Name=2|Designator=2|SwapIdPin=2|SwapIDPart=1|PinPropagationDelay=0.000000E+000
|RECORD=2|OwnerIndex=42|OwnerPartId=1|FormalType=1|Electrical=4|PinConglomerate=33|PinLength=10|Location.X=1181|Location.Y=886|Name=1|Designator=1|SwapIdPin=1|SwapIDPart=1|PinPropagationDelay=0.000000E+000
|RECORD=13|OwnerIndex=42|IsNotAccesible=T|IndexInSheet=20|OwnerPartId=1|Location.X=1181|Location.Y=878|Location.Y_Frac=50000|Corner.X=1181|Corner.Y=876|LineWidth=1|Color=16711680
|RECORD=13|OwnerIndex=42|IsNotAccesible=T|IndexInSheet=21|OwnerPartId=1|Location.X=1181|Location.Y=886|Corner.X=1181|Corner.Y=883|Corner.Y_Frac=50000|LineWidth=1|Color=16711680
|RECORD=13|OwnerIndex=42|IsNotAccesible=T|IndexInSheet=22|OwnerPartId=1|Location.X=1186|Location.Y=878|Location.Y_Frac=50000|Corner.X=1176|Corner.Y=878|Corner.Y_Frac=50000|LineWidth=1|Color=16711680
|RECORD=13|OwnerIndex=42|IsNotAccesible=T|IndexInSheet=23|OwnerPartId=1|Location.X=1186|Location.Y=883|Location.Y_Frac=50000|Corner.X=1176|Corner.Y=883|Corner.Y_Frac=50000|LineWidth=1|Color=16711680
|RECORD=41|OwnerIndex=42|IndexInSheet=24|OwnerPartId=-1|Location.X=1167|Location.Y=919|Location.Y_Frac=98951|Color=8388608|FontID=1|IsHidden=T|Text=<VALENTIUM>|Name=VALENTIUM PART NUM
|RECORD=34|OwnerIndex=42|IndexInSheet=-1|OwnerPartId=-1|Location.X=1191|Location.Y=886|Color=8388608|FontID=1|Text=C62|Name=Designator|ReadOnlyState=1
|RECORD=41|OwnerIndex=42|IndexInSheet=-1|OwnerPartId=-1|Location.X=1188|Location.X_Frac=50000|Location.Y=841|Color=8388608|FontID=1|IsHidden=T|Text=CAP_0805_10UF_25V|Name=Comment
|RECORD=44|OwnerIndex=42
|RECORD=45|OwnerIndex=72|IndexInSheet=-1|Description=Chip Capacitor, 0805, 2-Leads, Body 2.00x1.25mm, IPC Medium Density|UseComponentLibrary=T|ModelName=CAPC2012X14N|ModelType=PCBLIB|DatafileCount=1|ModelDatafileEntity0=CAPC2012X14N|ModelDatafileKind0=PCBLib|IsCurrent=T|DatalinksLocked=T|DatabaseDatalinksLocked=T|IntegratedModel=T|DatabaseModel=T
|RECORD=46|OwnerIndex=73
|RECORD=48|OwnerIndex=73
|RECORD=1|LibReference=MAC-SA5X|ComponentDescription=MOD, MAC, MAC-SA5X, ATOMIC CLOCK|PartCount=3|DisplayModeCount=1|IndexInSheet=27|OwnerPartId=-1|Location.X=768|Location.Y=927|CurrentPartId=1|LibraryPath=*|SourceLibraryName=Modules.IntLib|TargetFileName=*|AreaColor=11599871|Color=128|PartIDLocked=F|DesignItemId=MAC-SA5X|AllPinCount=28
|RECORD=41|OwnerIndex=76|OwnerPartId=-1|Location.X=666|Location.Y=947|Color=8388608|FontID=8|IsHidden=T|Text=3/22/2006 1:36:44 PM|Name=MODIFY DATE
|RECORD=41|OwnerIndex=76|IndexInSheet=1|OwnerPartId=-1|Location.X=666|Location.Y=947|Color=8388608|FontID=8|IsHidden=T|Text=MAC-SA5X|Name=MFG PART NUM
|RECORD=41|OwnerIndex=76|IndexInSheet=2|OwnerPartId=-1|Location.X=666|Location.Y=947|Color=8388608|FontID=8|IsHidden=T|Text=MOD|Name=CATEGORY
|RECORD=41|OwnerIndex=76|IndexInSheet=3|OwnerPartId=-1|Location.X=666|Location.Y=947|Color=8388608|FontID=8|IsHidden=T|Name=DATE
|RECORD=41|OwnerIndex=76|IndexInSheet=4|OwnerPartId=-1|Location.X=666|Location.Y=947|Color=8388608|FontID=8|IsHidden=T|Text=MICROCHIP|Name=MFG NAME
|RECORD=41|OwnerIndex=76|IndexInSheet=5|OwnerPartId=-1|Location.X=666|Location.Y=947|Color=8388608|FontID=8|IsHidden=T|Text=85C|Name=MAXTEMP
|RECORD=41|OwnerIndex=76|IndexInSheet=6|OwnerPartId=-1|Location.X=666|Location.Y=947|Color=8388608|FontID=8|IsHidden=T|Text=-40C|Name=MINTEMP
|RECORD=41|OwnerIndex=76|IndexInSheet=7|OwnerPartId=-1|Location.X=666|Location.Y=947|Color=8388608|FontID=8|IsHidden=T|Text=AEC-Q200|Name=OTHER
|RECORD=41|OwnerIndex=76|IndexInSheet=8|OwnerPartId=-1|Location.X=666|Location.Y=947|Color=8388608|FontID=8|IsHidden=T|Text=ATOMIC CLOCK|Name=P1
|RECORD=41|OwnerIndex=76|IndexInSheet=9|OwnerPartId=-1|Location.X=666|Location.Y=947|Color=8388608|FontID=8|IsHidden=T|Name=P2
|RECORD=41|OwnerIndex=76|IndexInSheet=10|OwnerPartId=-1|Location.X=666|Location.Y=947|Color=8388608|FontID=8|IsHidden=T|Name=P3
|RECORD=41|OwnerIndex=76|IndexInSheet=11|OwnerPartId=-1|Location.X=666|Location.Y=947|Color=8388608|FontID=8|IsHidden=T|Name=SIZE
|RECORD=41|OwnerIndex=76|IndexInSheet=12|OwnerPartId=-1|Location.X=666|Location.Y=947|Color=8388608|FontID=8|IsHidden=T|Name=SUB
|RECORD=41|OwnerIndex=76|IndexInSheet=13|OwnerPartId=-1|Location.X=666|Location.Y=947|Color=8388608|FontID=1|IsHidden=T|Text=*|Name=SHEETPART
|RECORD=41|OwnerIndex=76|IndexInSheet=14|OwnerPartId=-1|Location.X=666|Location.Y=947|Color=8388608|FontID=1|IsHidden=T|Text=MOD, MAC, MAC-SA5X, ATOMIC CLOCK|Name=DESC
|RECORD=41|OwnerIndex=76|IndexInSheet=15|OwnerPartId=-1|Location.X=666|Location.Y=947|Color=8388608|FontID=1|IsHidden=T|Text=<V PART NUM>|Name=VELENTIUM PART NUM
|RECORD=14|OwnerIndex=76|IsNotAccesible=T|IndexInSheet=16|OwnerPartId=1|Location.X=698|Location.Y=897|Corner.X=848|Corner.Y=947|Color=128|AreaColor=11599871|IsSolid=T
|RECORD=2|OwnerIndex=76|OwnerPartId=1|FormalType=1|Electrical=4|PinConglomerate=58|PinLength=30|Location.X=698|Location.Y=937|Name=FREQ CTRL IN|Designator=P1|PinPropagationDelay=0.000000E+000
|RECORD=2|OwnerIndex=76|OwnerPartId=1|FormalType=1|Electrical=4|PinConglomerate=58|PinLength=30|Location.X=698|Location.Y=927|Name=GND (CASE)|Designator=P2|PinPropagationDelay=0.000000E+000
|RECORD=2|OwnerIndex=76|OwnerPartId=1|FormalType=1|Electrical=4|PinConglomerate=58|PinLength=30|Location.X=698|Location.Y=917|Name=RF OUT|Designator=P3|PinPropagationDelay=0.000000E+000
|RECORD=2|OwnerIndex=76|OwnerPartId=1|FormalType=1|Electrical=4|PinConglomerate=58|PinLength=30|Location.X=698|Location.Y=907|Name=GND (SUPPLY & SIGNAL)|Designator=P4|PinPropagationDelay=0.000000E+000
|RECORD=2|OwnerIndex=76|OwnerPartId=1|FormalType=1|Electrical=4|PinConglomerate=56|PinLength=30|Location.X=848|Location.Y=907|Name=VCC|Designator=P5|PinPropagationDelay=0.000000E+000
|RECORD=2|OwnerIndex=76|OwnerPartId=1|FormalType=1|Electrical=4|PinConglomerate=56|PinLength=30|Location.X=848|Location.Y=917|Name=BITE|Designator=P6|PinPropagationDelay=0.000000E+000
|RECORD=2|OwnerIndex=76|OwnerPartId=1|FormalType=1|Electrical=4|PinConglomerate=56|PinLength=30|Location.X=848|Location.Y=927|Name=RS-232 TX|Designator=P7|PinPropagationDelay=0.000000E+000
|RECORD=2|OwnerIndex=76|OwnerPartId=1|FormalType=1|Electrical=4|PinConglomerate=56|PinLength=30|Location.X=848|Location.Y=937|Name=RS-232 RX|Designator=P8|PinPropagationDelay=0.000000E+000
|RECORD=41|OwnerIndex=76|IndexInSheet=25|OwnerPartId=-1|Location.X=698|Location.Y=851|Color=8388608|FontID=8|Text=RV-3049-C3|Name=VALUE
|RECORD=14|OwnerIndex=76|IsNotAccesible=T|IndexInSheet=26|OwnerPartId=2|Location.X=708|Location.Y=857|Corner.X=828|Corner.Y=987|Color=128|AreaColor=11599871|IsSolid=T
|RECORD=2|OwnerIndex=76|OwnerPartId=2|FormalType=1|Electrical=4|PinConglomerate=58|PinLength=30|Location.X=708|Location.Y=977|Name=PPS-IN 1+|Designator=1|PinPropagationDelay=0.000000E+000
|RECORD=2|OwnerIndex=76|OwnerPartId=2|FormalType=1|Electrical=4|PinConglomerate=56|PinLength=30|Location.X=828|Location.Y=977|Name=USB DATA +|Designator=2|PinPropagationDelay=0.000000E+000
|RECORD=2|OwnerIndex=76|OwnerPartId=2|FormalType=1|Electrical=4|PinConglomerate=58|PinLength=30|Location.X=708|Location.Y=967|Name=PPS-IN 1-|Designator=3|PinPropagationDelay=0.000000E+000
|RECORD=2|OwnerIndex=76|OwnerPartId=2|FormalType=1|Electrical=4|PinConglomerate=56|PinLength=30|Location.X=828|Location.Y=967|Name=USB DATA -|Designator=4|PinPropagationDelay=0.000000E+000
|RECORD=2|OwnerIndex=76|OwnerPartId=2|FormalType=1|Electrical=4|PinConglomerate=58|PinLength=30|Location.X=708|Location.Y=957|Name=PPS-IN 0+|Designator=5|PinPropagationDelay=0.000000E+000
|RECORD=2|OwnerIndex=76|OwnerPartId=2|FormalType=1|Electrical=4|PinConglomerate=56|PinLength=30|Location.X=828|Location.Y=957|Name=USB POWER|Designator=6|PinPropagationDelay=0.000000E+000
|RECORD=2|OwnerIndex=76|OwnerPartId=2|FormalType=1|Electrical=4|PinConglomerate=58|PinLength=30|Location.X=708|Location.Y=947|Name=PPS-IN 0-|Designator=7|PinPropagationDelay=0.000000E+000
|RECORD=2|OwnerIndex=76|OwnerPartId=2|FormalType=1|Electrical=4|PinConglomerate=56|PinLength=30|Location.X=828|Location.Y=887|Name=GND|Designator=8|PinPropagationDelay=0.000000E+000
|RECORD=2|OwnerIndex=76|OwnerPartId=2|FormalType=1|Electrical=4|PinConglomerate=56|PinLength=30|Location.X=828|Location.Y=877|Name=GND|Designator=9|PinPropagationDelay=0.000000E+000
|RECORD=2|OwnerIndex=76|OwnerPartId=2|FormalType=1|Electrical=4|PinConglomerate=58|PinLength=30|Location.X=708|Location.Y=927|Name=NC|Designator=10|PinPropagationDelay=0.000000E+000
|RECORD=2|OwnerIndex=76|OwnerPartId=2|FormalType=1|Electrical=4|PinConglomerate=58|PinLength=30|Location.X=708|Location.Y=917|Name=NC|Designator=11|PinPropagationDelay=0.000000E+000
|RECORD=2|OwnerIndex=76|OwnerPartId=2|FormalType=1|Electrical=4|PinConglomerate=58|PinLength=30|Location.X=708|Location.Y=907|Name=NC|Designator=12|PinPropagationDelay=0.000000E+000
|RECORD=2|OwnerIndex=76|OwnerPartId=2|FormalType=1|Electrical=4|PinConglomerate=58|PinLength=30|Location.X=708|Location.Y=897|Name=NC|Designator=13|PinPropagationDelay=0.000000E+000
|RECORD=2|OwnerIndex=76|OwnerPartId=2|FormalType=1|Electrical=4|PinConglomerate=58|PinLength=30|Location.X=708|Location.Y=887|Name=NC|Designator=14|PinPropagationDelay=0.000000E+000
|RECORD=2|OwnerIndex=76|OwnerPartId=2|FormalType=1|Electrical=4|PinConglomerate=56|PinLength=30|Location.X=828|Location.Y=867|Name=GND|Designator=15|PinPropagationDelay=0.000000E+000
|RECORD=2|OwnerIndex=76|OwnerPartId=2|FormalType=1|Electrical=4|PinConglomerate=58|PinLength=30|Location.X=708|Location.Y=877|Name=NC|Designator=16|PinPropagationDelay=0.000000E+000
|RECORD=2|OwnerIndex=76|OwnerPartId=2|FormalType=1|Electrical=4|PinConglomerate=56|PinLength=30|Location.X=828|Location.Y=937|Name=PPS-OUT +|Designator=17|PinPropagationDelay=0.000000E+000
|RECORD=2|OwnerIndex=76|OwnerPartId=2|FormalType=1|Electrical=4|PinConglomerate=58|PinLength=30|Location.X=708|Location.Y=867|Name=NC|Designator=18|PinPropagationDelay=0.000000E+000
|RECORD=2|OwnerIndex=76|OwnerPartId=2|FormalType=1|Electrical=4|PinConglomerate=56|PinLength=30|Location.X=828|Location.Y=927|Name=PPS-OUT -|Designator=19|PinPropagationDelay=0.000000E+000
|RECORD=2|OwnerIndex=76|OwnerPartId=2|FormalType=1|Electrical=4|PinConglomerate=56|PinLength=30|Location.X=828|Location.Y=907|Name=ALARM|Designator=20|PinPropagationDelay=0.000000E+000
|RECORD=2|OwnerIndex=76|OwnerPartId=1|FormalType=1|Electrical=4|PinConglomerate=56|PinLength=30|Location.X=850|Location.Y=890|Name=PPS-IN|Designator=P9|PinPropagationDelay=0.000000E+000
|RECORD=2|OwnerIndex=76|OwnerPartId=1|FormalType=1|Electrical=4|PinConglomerate=56|PinLength=30|Location.X=850|Location.Y=880|Name=PPS-OUT|Designator=P10|PinPropagationDelay=0.000000E+000
|RECORD=34|OwnerIndex=76|IndexInSheet=-1|OwnerPartId=-1|Location.X=698|Location.Y=947|Color=8388608|FontID=1|Text=U10|Name=Designator|ReadOnlyState=1
|RECORD=41|OwnerIndex=76|IndexInSheet=-1|OwnerPartId=-1|Location.X=666|Location.Y=947|Color=8388608|FontID=1|IsHidden=T|Text=="MFG PART NUM"|Name=Comment
|RECORD=44|OwnerIndex=76
|RECORD=45|OwnerIndex=158|IndexInSheet=-1|ModelName=SA53|ModelType=PCBLIB|DatafileCount=1|ModelDatafileEntity0=SA53|ModelDatafileKind0=PCBLib|IsCurrent=T|IntegratedModel=T|DatabaseModel=T
|RECORD=46|OwnerIndex=159
|RECORD=48|OwnerIndex=159
|RECORD=1|LibReference=MAC-SA5X|ComponentDescription=MOD, MAC, MAC-SA5X, ATOMIC CLOCK|PartCount=3|DisplayModeCount=1|IndexInSheet=28|OwnerPartId=-1|Location.X=700|Location.Y=610|CurrentPartId=2|LibraryPath=*|SourceLibraryName=Modules.IntLib|TargetFileName=*|AreaColor=11599871|Color=128|PartIDLocked=F|DesignItemId=MAC-SA5X|AllPinCount=28
|RECORD=41|OwnerIndex=162|OwnerPartId=-1|Location.X=700|Location.Y=610|Color=8388608|FontID=8|IsHidden=T|Text=3/22/2006 1:36:44 PM|Name=MODIFY DATE
|RECORD=41|OwnerIndex=162|IndexInSheet=1|OwnerPartId=-1|Location.X=700|Location.Y=610|Color=8388608|FontID=8|IsHidden=T|Text=MAC-SA5X|Name=MFG PART NUM
|RECORD=41|OwnerIndex=162|IndexInSheet=2|OwnerPartId=-1|Location.X=668|Location.Y=642|Color=8388608|FontID=8|IsHidden=T|Text=MOD|Name=CATEGORY
|RECORD=41|OwnerIndex=162|IndexInSheet=3|OwnerPartId=-1|Location.X=668|Location.Y=642|Color=8388608|FontID=8|IsHidden=T|Name=DATE
|RECORD=41|OwnerIndex=162|IndexInSheet=4|OwnerPartId=-1|Location.X=668|Location.Y=642|Color=8388608|FontID=8|IsHidden=T|Text=MICROCHIP|Name=MFG NAME
|RECORD=41|OwnerIndex=162|IndexInSheet=5|OwnerPartId=-1|Location.X=668|Location.Y=642|Color=8388608|FontID=8|IsHidden=T|Text=85C|Name=MAXTEMP
|RECORD=41|OwnerIndex=162|IndexInSheet=6|OwnerPartId=-1|Location.X=668|Location.Y=642|Color=8388608|FontID=8|IsHidden=T|Text=-40C|Name=MINTEMP
|RECORD=41|OwnerIndex=162|IndexInSheet=7|OwnerPartId=-1|Location.X=668|Location.Y=642|Color=8388608|FontID=8|IsHidden=T|Text=AEC-Q200|Name=OTHER
|RECORD=41|OwnerIndex=162|IndexInSheet=8|OwnerPartId=-1|Location.X=668|Location.Y=642|Color=8388608|FontID=8|IsHidden=T|Text=ATOMIC CLOCK|Name=P1
|RECORD=41|OwnerIndex=162|IndexInSheet=9|OwnerPartId=-1|Location.X=668|Location.Y=642|Color=8388608|FontID=8|IsHidden=T|Name=P2
|RECORD=41|OwnerIndex=162|IndexInSheet=10|OwnerPartId=-1|Location.X=668|Location.Y=642|Color=8388608|FontID=8|IsHidden=T|Name=P3
|RECORD=41|OwnerIndex=162|IndexInSheet=11|OwnerPartId=-1|Location.X=668|Location.Y=642|Color=8388608|FontID=8|IsHidden=T|Name=SIZE
|RECORD=41|OwnerIndex=162|IndexInSheet=12|OwnerPartId=-1|Location.X=668|Location.Y=642|Color=8388608|FontID=8|IsHidden=T|Name=SUB
|RECORD=41|OwnerIndex=162|IndexInSheet=13|OwnerPartId=-1|Location.X=668|Location.Y=438|Color=8388608|FontID=1|IsHidden=T|Text=*|Name=SHEETPART
|RECORD=41|OwnerIndex=162|IndexInSheet=14|OwnerPartId=-1|Location.X=668|Location.Y=642|Color=8388608|FontID=1|IsHidden=T|Text=MOD, MAC, MAC-SA5X, ATOMIC CLOCK|Name=DESC
|RECORD=41|OwnerIndex=162|IndexInSheet=15|OwnerPartId=-1|Location.X=658|Location.Y=642|Color=8388608|FontID=1|IsHidden=T|Text=<V PART NUM>|Name=VELENTIUM PART NUM
|RECORD=14|OwnerIndex=162|IsNotAccesible=T|IndexInSheet=16|OwnerPartId=1|Location.X=630|Location.Y=580|Corner.X=780|Corner.Y=630|Color=128|AreaColor=11599871|IsSolid=T
|RECORD=2|OwnerIndex=162|OwnerPartId=1|FormalType=1|Electrical=4|PinConglomerate=58|PinLength=30|Location.X=630|Location.Y=620|Name=FREQ CTRL IN|Designator=P1|SwapIDPart=Ž&Ž||PinPropagationDelay=0.000000E+000
|RECORD=2|OwnerIndex=162|OwnerPartId=1|FormalType=1|Electrical=4|PinConglomerate=58|PinLength=30|Location.X=630|Location.Y=610|Name=GND (CASE)|Designator=P2|SwapIDPart=Ž&Ž||PinPropagationDelay=0.000000E+000
|RECORD=2|OwnerIndex=162|OwnerPartId=1|FormalType=1|Electrical=4|PinConglomerate=58|PinLength=30|Location.X=630|Location.Y=600|Name=RF OUT|Designator=P3|SwapIDPart=Ž&Ž||PinPropagationDelay=0.000000E+000
|RECORD=2|OwnerIndex=162|OwnerPartId=1|FormalType=1|Electrical=4|PinConglomerate=58|PinLength=30|Location.X=630|Location.Y=590|Name=GND (SUPPLY & SIGNAL)|Designator=P4|SwapIDPart=Ž&Ž||PinPropagationDelay=0.000000E+000
|RECORD=2|OwnerIndex=162|OwnerPartId=1|FormalType=1|Electrical=4|PinConglomerate=56|PinLength=30|Location.X=780|Location.Y=590|Name=VCC|Designator=P5|SwapIDPart=Ž&Ž||PinPropagationDelay=0.000000E+000
|RECORD=2|OwnerIndex=162|OwnerPartId=1|FormalType=1|Electrical=4|PinConglomerate=56|PinLength=30|Location.X=780|Location.Y=600|Name=BITE|Designator=P6|SwapIDPart=Ž&Ž||PinPropagationDelay=0.000000E+000
|RECORD=2|OwnerIndex=162|OwnerPartId=1|FormalType=1|Electrical=4|PinConglomerate=56|PinLength=30|Location.X=780|Location.Y=610|Name=RS-232 TX|Designator=P7|SwapIDPart=Ž&Ž||PinPropagationDelay=0.000000E+000
|RECORD=2|OwnerIndex=162|OwnerPartId=1|FormalType=1|Electrical=4|PinConglomerate=56|PinLength=30|Location.X=780|Location.Y=620|Name=RS-232 RX|Designator=P8|SwapIDPart=Ž&Ž||PinPropagationDelay=0.000000E+000
|RECORD=41|OwnerIndex=162|IndexInSheet=25|OwnerPartId=-1|Location.X=640|Location.Y=528|Color=8388608|FontID=8|Text=RV-3049-C3|Name=VALUE
|RECORD=14|OwnerIndex=162|IsNotAccesible=T|IndexInSheet=26|OwnerPartId=2|Location.X=640|Location.Y=540|Corner.X=760|Corner.Y=670|Color=128|AreaColor=11599871|IsSolid=T
|RECORD=2|OwnerIndex=162|OwnerPartId=2|FormalType=1|Electrical=4|PinConglomerate=58|PinLength=30|Location.X=640|Location.Y=660|Name=PPS-IN 1+|Designator=1|SwapIDPart=Ž&Ž||PinPropagationDelay=0.000000E+000
|RECORD=2|OwnerIndex=162|OwnerPartId=2|FormalType=1|Electrical=4|PinConglomerate=56|PinLength=30|Location.X=760|Location.Y=660|Name=USB DATA +|Designator=2|SwapIDPart=Ž&Ž||PinPropagationDelay=0.000000E+000
|RECORD=2|OwnerIndex=162|OwnerPartId=2|FormalType=1|Electrical=4|PinConglomerate=58|PinLength=30|Location.X=640|Location.Y=650|Name=PPS-IN 1-|Designator=3|SwapIDPart=Ž&Ž||PinPropagationDelay=0.000000E+000
|RECORD=2|OwnerIndex=162|OwnerPartId=2|FormalType=1|Electrical=4|PinConglomerate=56|PinLength=30|Location.X=760|Location.Y=650|Name=USB DATA -|Designator=4|SwapIDPart=Ž&Ž||PinPropagationDelay=0.000000E+000
|RECORD=2|OwnerIndex=162|OwnerPartId=2|FormalType=1|Electrical=4|PinConglomerate=58|PinLength=30|Location.X=640|Location.Y=640|Name=PPS-IN 0+|Designator=5|SwapIDPart=Ž&Ž||PinPropagationDelay=0.000000E+000
|RECORD=2|OwnerIndex=162|OwnerPartId=2|FormalType=1|Electrical=4|PinConglomerate=56|PinLength=30|Location.X=760|Location.Y=640|Name=USB POWER|Designator=6|SwapIDPart=Ž&Ž||PinPropagationDelay=0.000000E+000
|RECORD=2|OwnerIndex=162|OwnerPartId=2|FormalType=1|Electrical=4|PinConglomerate=58|PinLength=30|Location.X=640|Location.Y=630|Name=PPS-IN 0-|Designator=7|SwapIDPart=Ž&Ž||PinPropagationDelay=0.000000E+000
|RECORD=2|OwnerIndex=162|OwnerPartId=2|FormalType=1|Electrical=4|PinConglomerate=56|PinLength=30|Location.X=760|Location.Y=570|Name=GND|Designator=8|SwapIDPart=Ž&Ž||PinPropagationDelay=0.000000E+000
|RECORD=2|OwnerIndex=162|OwnerPartId=2|FormalType=1|Electrical=4|PinConglomerate=56|PinLength=30|Location.X=760|Location.Y=560|Name=GND|Designator=9|SwapIDPart=Ž&Ž||PinPropagationDelay=0.000000E+000
|RECORD=2|OwnerIndex=162|OwnerPartId=2|FormalType=1|Electrical=4|PinConglomerate=58|PinLength=30|Location.X=640|Location.Y=610|Name=NC|Designator=10|SwapIDPart=Ž&Ž||PinPropagationDelay=0.000000E+000
|RECORD=2|OwnerIndex=162|OwnerPartId=2|FormalType=1|Electrical=4|PinConglomerate=58|PinLength=30|Location.X=640|Location.Y=600|Name=NC|Designator=11|SwapIDPart=Ž&Ž||PinPropagationDelay=0.000000E+000
|RECORD=2|OwnerIndex=162|OwnerPartId=2|FormalType=1|Electrical=4|PinConglomerate=58|PinLength=30|Location.X=640|Location.Y=590|Name=NC|Designator=12|SwapIDPart=Ž&Ž||PinPropagationDelay=0.000000E+000
|RECORD=2|OwnerIndex=162|OwnerPartId=2|FormalType=1|Electrical=4|PinConglomerate=58|PinLength=30|Location.X=640|Location.Y=580|Name=NC|Designator=13|SwapIDPart=Ž&Ž||PinPropagationDelay=0.000000E+000
|RECORD=2|OwnerIndex=162|OwnerPartId=2|FormalType=1|Electrical=4|PinConglomerate=58|PinLength=30|Location.X=640|Location.Y=570|Name=NC|Designator=14|SwapIDPart=Ž&Ž||PinPropagationDelay=0.000000E+000
|RECORD=2|OwnerIndex=162|OwnerPartId=2|FormalType=1|Electrical=4|PinConglomerate=56|PinLength=30|Location.X=760|Location.Y=550|Name=GND|Designator=15|SwapIDPart=Ž&Ž||PinPropagationDelay=0.000000E+000
|RECORD=2|OwnerIndex=162|OwnerPartId=2|FormalType=1|Electrical=4|PinConglomerate=58|PinLength=30|Location.X=640|Location.Y=560|Name=NC|Designator=16|SwapIDPart=Ž&Ž||PinPropagationDelay=0.000000E+000
|RECORD=2|OwnerIndex=162|OwnerPartId=2|FormalType=1|Electrical=4|PinConglomerate=56|PinLength=30|Location.X=760|Location.Y=620|Name=PPS-OUT +|Designator=17|SwapIDPart=Ž&Ž||PinPropagationDelay=0.000000E+000
|RECORD=2|OwnerIndex=162|OwnerPartId=2|FormalType=1|Electrical=4|PinConglomerate=58|PinLength=30|Location.X=640|Location.Y=550|Name=NC|Designator=18|SwapIDPart=Ž&Ž||PinPropagationDelay=0.000000E+000
|RECORD=2|OwnerIndex=162|OwnerPartId=2|FormalType=1|Electrical=4|PinConglomerate=56|PinLength=30|Location.X=760|Location.Y=610|Name=PPS-OUT -|Designator=19|SwapIDPart=Ž&Ž||PinPropagationDelay=0.000000E+000
|RECORD=2|OwnerIndex=162|OwnerPartId=2|FormalType=1|Electrical=4|PinConglomerate=56|PinLength=30|Location.X=760|Location.Y=590|Name=ALARM|Designator=20|SwapIDPart=Ž&Ž||PinPropagationDelay=0.000000E+000
|RECORD=34|OwnerIndex=162|IndexInSheet=-1|OwnerPartId=-1|Location.X=640|Location.Y=670|Color=8388608|FontID=1|Text=U10|Name=Designator|ReadOnlyState=1
|RECORD=41|OwnerIndex=162|IndexInSheet=-1|OwnerPartId=-1|Location.X=720|Location.Y=570|Color=8388608|FontID=1|IsHidden=T|Text=="MFG PART NUM"|Name=Comment
|RECORD=44|OwnerIndex=162
|RECORD=45|OwnerIndex=240|IndexInSheet=-1|ModelName=SA53|ModelType=PCBLIB|DatafileCount=1|ModelDatafileEntity0=SA53|ModelDatafileKind0=PCBLib|IsCurrent=T|IntegratedModel=T|DatabaseModel=T
|RECORD=46|OwnerIndex=241
|RECORD=48|OwnerIndex=241
|RECORD=1|LibReference=CAP|ComponentDescription=C0603X104K5RACAUTO|PartCount=2|DisplayModeCount=2|IndexInSheet=29|OwnerPartId=-1|Location.X=1230|Location.Y=880|Orientation=1|CurrentPartId=1|SourceLibraryName=Altium Content Vault|TargetFileName=*|AreaColor=11599871|Color=128|PartIDLocked=F|DesignItemId=CMP-2006-00003-1|AllPinCount=2
|RECORD=2|OwnerIndex=244|OwnerPartId=1|OwnerPartDisplayMode=1|FormalType=1|Electrical=4|PinConglomerate=35|PinLength=10|Location.X=1240|Location.Y=880|Name=1|Designator=1|PinPropagationDelay=0.000000E+000
|RECORD=2|OwnerIndex=244|OwnerPartId=1|OwnerPartDisplayMode=1|FormalType=1|Electrical=4|PinConglomerate=33|PinLength=10|Location.X=1240|Location.Y=890|Name=2|Designator=2|PinPropagationDelay=0.000000E+000
|RECORD=13|OwnerIndex=244|IsNotAccesible=T|IndexInSheet=2|OwnerPartId=1|OwnerPartDisplayMode=1|Location.X=1248|Location.Y=880|Corner.X=1232|Corner.Y=880|LineWidth=1|Color=16711680
|RECORD=13|OwnerIndex=244|IsNotAccesible=T|IndexInSheet=3|OwnerPartId=1|OwnerPartDisplayMode=1|Location.X=1240|Location.Y=884|Corner.X=1240|Corner.Y=890|LineWidth=1|Color=16711680
|RECORD=12|OwnerIndex=244|IsNotAccesible=T|IndexInSheet=4|OwnerPartId=1|OwnerPartDisplayMode=1|Location.X=1240|Location.Y=900|Radius=16|LineWidth=1|StartAngle=241.000|EndAngle=270.000|Color=16711680
|RECORD=12|OwnerIndex=244|IsNotAccesible=T|IndexInSheet=5|OwnerPartId=1|OwnerPartDisplayMode=1|Location.X=1240|Location.Y=900|Radius=16|LineWidth=1|StartAngle=270.000|EndAngle=299.000|Color=16711680
|RECORD=2|OwnerIndex=244|OwnerPartId=1|FormalType=1|Electrical=4|PinConglomerate=35|PinLength=10|Location.X=1240|Location.Y=880|Name=1|Designator=1|PinPropagationDelay=0.000000E+000
|RECORD=2|OwnerIndex=244|OwnerPartId=1|FormalType=1|Electrical=4|PinConglomerate=33|PinLength=10|Location.X=1240|Location.Y=890|Name=2|Designator=2|PinPropagationDelay=0.000000E+000
|RECORD=13|OwnerIndex=244|IsNotAccesible=T|IndexInSheet=8|OwnerPartId=1|Location.X=1232|Location.Y=887|Corner.X=1248|Corner.Y=887|LineWidth=1|Color=16711680
|RECORD=13|OwnerIndex=244|IsNotAccesible=T|IndexInSheet=9|OwnerPartId=1|Location.X=1248|Location.Y=883|Corner.X=1232|Corner.Y=883|LineWidth=1|Color=16711680
|RECORD=6|OwnerIndex=244|IsNotAccesible=T|IndexInSheet=10|OwnerPartId=1|LineWidth=1|Color=16711680|LocationCount=2|X1=1240|Y1=880|X2=1240|Y2=883
|RECORD=6|OwnerIndex=244|IsNotAccesible=T|IndexInSheet=11|OwnerPartId=1|LineWidth=1|Color=16711680|LocationCount=2|X1=1240|Y1=890|X2=1240|Y2=887
|RECORD=41|OwnerIndex=244|IndexInSheet=12|OwnerPartId=-1|Location.X=1231|Location.Y=902|Color=8388608|FontID=1|IsHidden=T|Text=Kemet|Name=Manufacturer
|RECORD=41|OwnerIndex=244|IndexInSheet=13|OwnerPartId=-1|Location.X=1231|Location.Y=902|Color=8388608|FontID=1|IsHidden=T|Text=C0603X104K5RACAUTO|Name=Part Number
|RECORD=34|OwnerIndex=244|IndexInSheet=-1|OwnerPartId=-1|Location.X=1249|Location.Y=881|Color=8388608|FontID=1|Text=C63|Name=Designator|ReadOnlyState=1
|RECORD=41|OwnerIndex=244|IndexInSheet=-1|OwnerPartId=-1|Location.X=1249|Location.Y=871|Color=8388608|FontID=1|Text=0.1uF|Name=Comment
|RECORD=44|OwnerIndex=244
|RECORD=45|OwnerIndex=265|IndexInSheet=-1|Description=Chip Capacitor, 2-Leads, Body 1.60x0.80mm, IPC Low Density|UseComponentLibrary=T|ModelName=CAPC1608X87X45ML20T05|ModelType=PCBLIB|DatafileCount=1|ModelDatafileEntity0=CAPC1608X87X45ML20T05|ModelDatafileKind0=PCBLib|IsCurrent=T|DatalinksLocked=T|DatabaseDatalinksLocked=T
|RECORD=46|OwnerIndex=266
|RECORD=48|OwnerIndex=266
|RECORD=41|OwnerIndex=268|IndexInSheet=-1|OwnerPartId=-1|Color=8388608|FontID=1|Text=2D|Name=Available Preview Images
|RECORD=45|OwnerIndex=265|IndexInSheet=-1|Description=Chip Capacitor, 2-Leads, Body 1.60x0.80mm, IPC High Density|UseComponentLibrary=T|ModelName=CAPC1608X87X45LL20T05|ModelType=PCBLIB|DatafileCount=1|ModelDatafileEntity0=CAPC1608X87X45LL20T05|ModelDatafileKind0=PCBLib|DatalinksLocked=T|DatabaseDatalinksLocked=T
|RECORD=46|OwnerIndex=270
|RECORD=48|OwnerIndex=270
|RECORD=41|OwnerIndex=272|IndexInSheet=-1|OwnerPartId=-1|Color=8388608|FontID=1|Text=2D|Name=Available Preview Images
|RECORD=45|OwnerIndex=265|IndexInSheet=-1|Description=Chip Capacitor, 2-Leads, Body 1.60x0.80mm, IPC Medium Density|UseComponentLibrary=T|ModelName=CAPC1608X87X45NL20T05|ModelType=PCBLIB|DatafileCount=1|ModelDatafileEntity0=CAPC1608X87X45NL20T05|ModelDatafileKind0=PCBLib|DatalinksLocked=T|DatabaseDatalinksLocked=T
|RECORD=46|OwnerIndex=274
|RECORD=48|OwnerIndex=274
|RECORD=41|OwnerIndex=276|IndexInSheet=-1|OwnerPartId=-1|Color=8388608|FontID=1|Text=2D|Name=Available Preview Images
|RECORD=41|IndexInSheet=30|OwnerPartId=-1|Color=8388608|FontID=1|IsHidden=T|Name=ConfigurationParameters|ReadOnlyState=1
|RECORD=41|IndexInSheet=31|OwnerPartId=-1|Color=8388608|FontID=1|IsHidden=T|Name=ConfiguratorName|ReadOnlyState=1
|RECORD=41|IndexInSheet=32|OwnerPartId=-1|Color=8388608|FontID=1|IsHidden=T|Name=VersionControl_RevNumber|ReadOnlyState=1
|RECORD=41|IndexInSheet=33|OwnerPartId=-1|Color=8388608|FontID=1|IsHidden=T|Name=IsUserConfigurable|ReadOnlyState=1
|RECORD=41|IndexInSheet=34|OwnerPartId=-1|Color=8388608|FontID=1|IsHidden=T|Name=VersionControl_ProjFolderRevNumber|ReadOnlyState=1
|RECORD=41|IndexInSheet=35|OwnerPartId=-1|Color=8388608|FontID=1|IsHidden=T|Name=SPICEModelCache|ReadOnlyState=1
|RECORD=1|LibReference=IN-LNDRV-DS90LV027AHM|ComponentDescription=Automotive LVDS Dual Differential Driver, 8-pin Narrow SOIC|PartCount=2|DisplayModeCount=1|IndexInSheet=36|OwnerPartId=-1|Location.X=1130|Location.Y=300|CurrentPartId=1|LibraryPath=*|SourceLibraryName=Altium Content Vault|TargetFileName=*|AreaColor=11599871|Color=128|PartIDLocked=T|DesignItemId=CMP-0058-01000-2|AllPinCount=8
|RECORD=14|OwnerIndex=284|IsNotAccesible=T|OwnerPartId=1|Location.X=1130|Location.Y=220|Corner.X=1200|Corner.Y=300|Color=128|AreaColor=11599871|IsSolid=T
|RECORD=2|OwnerIndex=284|OwnerPartId=1|FormalType=1|PinConglomerate=58|PinLength=20|Location.X=1130|Location.Y=290|Name=DI1|Designator=2|SwapIDPart=Ž&Ž||PinPropagationDelay=0.000000E+000
|RECORD=2|OwnerIndex=284|OwnerPartId=1|FormalType=1|PinConglomerate=58|PinLength=20|Location.X=1130|Location.Y=260|Name=DI2|Designator=3|SwapIDPart=Ž&Ž||PinPropagationDelay=0.000000E+000
|RECORD=2|OwnerIndex=284|OwnerPartId=1|FormalType=1|Electrical=2|PinConglomerate=56|PinLength=20|Location.X=1200|Location.Y=290|Name=DO+1|Designator=7|SwapIDPart=Ž&Ž||PinPropagationDelay=0.000000E+000
|RECORD=2|OwnerIndex=284|OwnerPartId=1|FormalType=1|Electrical=2|PinConglomerate=56|PinLength=20|Location.X=1200|Location.Y=260|Name=DO+2|Designator=6|SwapIDPart=Ž&Ž||PinPropagationDelay=0.000000E+000
|RECORD=2|OwnerIndex=284|OwnerPartId=1|FormalType=1|Electrical=2|PinConglomerate=56|PinLength=20|Location.X=1200|Location.Y=280|Name=DO-1|Designator=8|SwapIDPart=Ž&Ž||PinPropagationDelay=0.000000E+000
|RECORD=2|OwnerIndex=284|OwnerPartId=1|FormalType=1|Electrical=2|PinConglomerate=56|PinLength=20|Location.X=1200|Location.Y=250|Name=DO-2|Designator=5|SwapIDPart=Ž&Ž||PinPropagationDelay=0.000000E+000
|RECORD=2|OwnerIndex=284|OwnerPartId=1|FormalType=1|Electrical=7|PinConglomerate=56|PinLength=20|Location.X=1200|Location.Y=230|Name=GND|Designator=4|SwapIDPart=Ž&Ž||PinPropagationDelay=0.000000E+000
|RECORD=2|OwnerIndex=284|OwnerPartId=1|FormalType=1|Electrical=7|PinConglomerate=58|PinLength=20|Location.X=1130|Location.Y=230|Name=VCC|Designator=1|SwapIDPart=Ž&Ž||PinPropagationDelay=0.000000E+000
|RECORD=41|OwnerIndex=284|IndexInSheet=9|OwnerPartId=-1|Location.X=1108|Location.Y=300|Color=8388608|FontID=1|IsHidden=T|Text=Oct-2008|Name=DatasheetVersion
|RECORD=41|OwnerIndex=284|IndexInSheet=10|OwnerPartId=-1|Location.X=1108|Location.Y=300|Color=8388608|FontID=1|IsHidden=T|Text=8|Name=PinCount
|RECORD=41|OwnerIndex=284|IndexInSheet=11|OwnerPartId=-1|Location.X=1108|Location.Y=300|Color=8388608|FontID=1|IsHidden=T|Text=Component URLs added|Name=RevisionNote
|RECORD=41|OwnerIndex=284|IndexInSheet=12|OwnerPartId=-1|Location.X=1108|Location.Y=300|Color=8388608|FontID=1|IsHidden=T|Text=SOIC127P600-8|Name=Code_IPC
|RECORD=41|OwnerIndex=284|IndexInSheet=13|OwnerPartId=-1|Location.X=1108|Location.Y=300|Color=8388608|FontID=1|IsHidden=T|Text=National Semiconductor|Name=Manufacturer
|RECORD=41|OwnerIndex=284|IndexInSheet=14|OwnerPartId=-1|Location.X=1108|Location.Y=300|Color=8388608|FontID=1|IsHidden=T|Text=NSZXTT*90LV0*27AQM|Name=PackageTopMarking
|RECORD=41|OwnerIndex=284|IndexInSheet=15|OwnerPartId=-1|Location.X=1108|Location.Y=300|Color=8388608|FontID=1|IsHidden=T|Text=Interface IC|Name=CompType
|RECORD=41|OwnerIndex=284|IndexInSheet=16|OwnerPartId=-1|Location.X=1108|Location.Y=300|Color=8388608|FontID=7|IsHidden=T|Text=http://www.national.com/ds/DS/DS90LV027AQ.pdf|Name=ComponentLink1URL
|RECORD=41|OwnerIndex=284|IndexInSheet=17|OwnerPartId=-1|Location.X=1108|Location.Y=300|Color=8388608|FontID=1|IsHidden=T|Text=M08A Package Page|Name=ComponentLink3Description
|RECORD=41|OwnerIndex=284|IndexInSheet=18|OwnerPartId=-1|Location.X=1108|Location.Y=300|Color=8388608|FontID=1|IsHidden=T|Text=SOIC Narrow, 4.9 x 3.9 x 1.45mm, 8 Lead, 1.27mm Pitch|Name=PackageDescription
|RECORD=41|OwnerIndex=284|IndexInSheet=19|OwnerPartId=-1|Location.X=1108|Location.Y=300|Color=8388608|FontID=1|IsHidden=T|Text=DS90LV027AQ Web Page|Name=ComponentLink2Description
|RECORD=41|OwnerIndex=284|IndexInSheet=20|OwnerPartId=-1|Location.X=1108|Location.Y=300|Color=8388608|FontID=7|IsHidden=T|Text=http://www.national.com/pf/DS/DS90LV027AQ.html|Name=ComponentLink2URL
|RECORD=41|OwnerIndex=284|IndexInSheet=21|OwnerPartId=-1|Location.X=1108|Location.Y=300|Color=8388608|FontID=1|IsHidden=T|Text=Y|Name=RoHS
|RECORD=41|OwnerIndex=284|IndexInSheet=22|OwnerPartId=-1|Location.X=1108|Location.Y=300|Color=8388608|FontID=1|IsHidden=T|Text=N|Name=PowerWise
|RECORD=41|OwnerIndex=284|IndexInSheet=23|OwnerPartId=-1|Location.X=1108|Location.Y=300|Color=8388608|FontID=1|IsHidden=T|Text=MS-012-AA|Name=Code_JEDEC
|RECORD=41|OwnerIndex=284|IndexInSheet=24|OwnerPartId=-1|Location.X=1108|Location.Y=300|Color=8388608|FontID=1|IsHidden=T|Text=M08A|Name=PackageReference
|RECORD=41|OwnerIndex=284|IndexInSheet=25|OwnerPartId=-1|Location.X=1108|Location.Y=300|Color=8388608|FontID=1|IsHidden=T|Text=revM, May-2009|Name=PackageVersion
|RECORD=41|OwnerIndex=284|IndexInSheet=26|OwnerPartId=-1|Location.X=1108|Location.Y=300|Color=8388608|FontID=1|IsHidden=T|Text=DS90LV027AQ Datasheet|Name=ComponentLink1Description
|RECORD=41|OwnerIndex=284|IndexInSheet=27|OwnerPartId=-1|Location.X=1108|Location.Y=300|Color=8388608|FontID=7|IsHidden=T|Text=http://www.national.com/packaging/folders/m08a.html|Name=ComponentLink3URL
|RECORD=34|OwnerIndex=284|IndexInSheet=-1|OwnerPartId=-1|Location.X=1130|Location.Y=300|Color=8388608|FontID=1|Text=U3|Name=Designator|ReadOnlyState=1
|RECORD=41|OwnerIndex=284|IndexInSheet=-1|OwnerPartId=-1|Location.X=1130|Location.Y=210|Color=8388608|FontID=1|Text=DS90LV027AQMA|Name=Comment
|RECORD=44|OwnerIndex=284
|RECORD=45|OwnerIndex=323|IndexInSheet=-1|Description=SOIC, 8-Leads, Body 4.9x3.9mm, Pitch 1.27mm, IPC Medium Density|UseComponentLibrary=T|ModelName=M08A_N|ModelType=PCBLIB|DatafileCount=1|ModelDatafileEntity0=M08A_N|ModelDatafileKind0=PCBLib|IsCurrent=T|DatalinksLocked=T|DatabaseDatalinksLocked=T
|RECORD=46|OwnerIndex=324
|RECORD=48|OwnerIndex=324
|RECORD=41|OwnerIndex=326|IndexInSheet=-1|OwnerPartId=-1|Color=8388608|FontID=1|IsHidden=T|Text=2D|Name=Available Preview Images
|RECORD=45|OwnerIndex=323|IndexInSheet=-1|Description=SOIC, 8-Leads, Body 4.9x3.9mm, Pitch 1.27mm, IPC Low Density|UseComponentLibrary=T|ModelName=M08A_M|ModelType=PCBLIB|DatafileCount=1|ModelDatafileEntity0=M08A_M|ModelDatafileKind0=PCBLib|DatalinksLocked=T|DatabaseDatalinksLocked=T
|RECORD=46|OwnerIndex=328
|RECORD=48|OwnerIndex=328
|RECORD=41|OwnerIndex=330|IndexInSheet=-1|OwnerPartId=-1|Color=8388608|FontID=1|IsHidden=T|Text=2D|Name=Available Preview Images
|RECORD=45|OwnerIndex=323|IndexInSheet=-1|Description=SOIC, 8-Leads, Body 4.9x3.9mm, Pitch 1.27mm, IPC High Density|UseComponentLibrary=T|ModelName=M08A_L|ModelType=PCBLIB|DatafileCount=1|ModelDatafileEntity0=M08A_L|ModelDatafileKind0=PCBLib|DatalinksLocked=T|DatabaseDatalinksLocked=T
|RECORD=46|OwnerIndex=332
|RECORD=48|OwnerIndex=332
|RECORD=41|OwnerIndex=334|IndexInSheet=-1|OwnerPartId=-1|Color=8388608|FontID=1|IsHidden=T|Text=2D|Name=Available Preview Images
|RECORD=1|LibReference=IN-LNRX-DS90LV028AHM|ComponentDescription=Automotive LVDS Dual Differential Line Receiver, 8-pin Narrow SOIC|PartCount=2|DisplayModeCount=1|IndexInSheet=37|OwnerPartId=-1|Location.X=340|Location.Y=280|CurrentPartId=1|LibraryPath=*|SourceLibraryName=Altium Content Vault|TargetFileName=*|AreaColor=11599871|Color=128|PartIDLocked=T|DesignItemId=CMP-0058-01010-2|AllPinCount=8
|RECORD=14|OwnerIndex=336|IsNotAccesible=T|OwnerPartId=1|Location.X=340|Location.Y=200|Corner.X=420|Corner.Y=280|Color=128|AreaColor=11599871|IsSolid=T
|RECORD=2|OwnerIndex=336|OwnerPartId=1|FormalType=1|PinConglomerate=58|PinLength=20|Location.X=340|Location.Y=260|Name=RIN1-|Designator=1|SwapIDPart=Ž&Ž||PinPropagationDelay=0.000000E+000
|RECORD=2|OwnerIndex=336|OwnerPartId=1|FormalType=1|PinConglomerate=58|PinLength=20|Location.X=340|Location.Y=270|Name=RIN1+|Designator=2|SwapIDPart=Ž&Ž||PinPropagationDelay=0.000000E+000
|RECORD=2|OwnerIndex=336|OwnerPartId=1|FormalType=1|PinConglomerate=58|PinLength=20|Location.X=340|Location.Y=240|Name=RIN2+|Designator=3|SwapIDPart=Ž&Ž||PinPropagationDelay=0.000000E+000
|RECORD=2|OwnerIndex=336|OwnerPartId=1|FormalType=1|PinConglomerate=58|PinLength=20|Location.X=340|Location.Y=230|Name=RIN2-|Designator=4|SwapIDPart=Ž&Ž||PinPropagationDelay=0.000000E+000
|RECORD=2|OwnerIndex=336|OwnerPartId=1|FormalType=1|Electrical=7|PinConglomerate=56|PinLength=20|Location.X=420|Location.Y=210|Name=GND|Designator=5|SwapIDPart=Ž&Ž||PinPropagationDelay=0.000000E+000
|RECORD=2|OwnerIndex=336|OwnerPartId=1|FormalType=1|Electrical=2|PinConglomerate=56|PinLength=20|Location.X=420|Location.Y=240|Name=ROUT2|Designator=6|SwapIDPart=Ž&Ž||PinPropagationDelay=0.000000E+000
|RECORD=2|OwnerIndex=336|OwnerPartId=1|FormalType=1|Electrical=2|PinConglomerate=56|PinLength=20|Location.X=420|Location.Y=270|Name=ROUT1|Designator=7|SwapIDPart=Ž&Ž||PinPropagationDelay=0.000000E+000
|RECORD=2|OwnerIndex=336|OwnerPartId=1|FormalType=1|Electrical=7|PinConglomerate=58|PinLength=20|Location.X=340|Location.Y=210|Name=VCC|Designator=8|SwapIDPart=Ž&Ž||PinPropagationDelay=0.000000E+000
|RECORD=41|OwnerIndex=336|IndexInSheet=9|OwnerPartId=-1|Location.X=318|Location.Y=280|Color=8388608|FontID=1|IsHidden=T|Text=National Semiconductor|Name=Manufacturer
|RECORD=41|OwnerIndex=336|IndexInSheet=10|OwnerPartId=-1|Location.X=318|Location.Y=280|Color=8388608|FontID=1|IsHidden=T|Text=Oct-2008|Name=DatasheetVersion
|RECORD=41|OwnerIndex=336|IndexInSheet=11|OwnerPartId=-1|Location.X=318|Location.Y=280|Color=8388608|FontID=1|IsHidden=T|Text=N|Name=PowerWise
|RECORD=41|OwnerIndex=336|IndexInSheet=12|OwnerPartId=-1|Location.X=318|Location.Y=280|Color=8388608|FontID=1|IsHidden=T|Text=M08A|Name=PackageReference
|RECORD=41|OwnerIndex=336|IndexInSheet=13|OwnerPartId=-1|Location.X=318|Location.Y=280|Color=8388608|FontID=1|IsHidden=T|Text=Component URLs added|Name=RevisionNote
|RECORD=41|OwnerIndex=336|IndexInSheet=14|OwnerPartId=-1|Location.X=318|Location.Y=280|Color=8388608|FontID=1|IsHidden=T|Text=MS-012-AA|Name=Code_JEDEC
|RECORD=41|OwnerIndex=336|IndexInSheet=15|OwnerPartId=-1|Location.X=318|Location.Y=280|Color=8388608|FontID=1|IsHidden=T|Text=revM, May-2009|Name=PackageVersion
|RECORD=41|OwnerIndex=336|IndexInSheet=16|OwnerPartId=-1|Location.X=318|Location.Y=280|Color=8388608|FontID=7|IsHidden=T|Text=http://www.national.com/ds/DS/DS90LV028AQ.pdf|Name=ComponentLink1URL
|RECORD=41|OwnerIndex=336|IndexInSheet=17|OwnerPartId=-1|Location.X=318|Location.Y=280|Color=8388608|FontID=1|IsHidden=T|Text=8|Name=PinCount
|RECORD=41|OwnerIndex=336|IndexInSheet=18|OwnerPartId=-1|Location.X=318|Location.Y=280|Color=8388608|FontID=1|IsHidden=T|Text=M08A Package Page|Name=ComponentLink3Description
|RECORD=41|OwnerIndex=336|IndexInSheet=19|OwnerPartId=-1|Location.X=318|Location.Y=280|Color=8388608|FontID=1|IsHidden=T|Text=DS90LV028AQ Datasheet|Name=ComponentLink1Description
|RECORD=41|OwnerIndex=336|IndexInSheet=20|OwnerPartId=-1|Location.X=318|Location.Y=280|Color=8388608|FontID=1|IsHidden=T|Text=SOIC127P600-8|Name=Code_IPC
|RECORD=41|OwnerIndex=336|IndexInSheet=21|OwnerPartId=-1|Location.X=318|Location.Y=280|Color=8388608|FontID=1|IsHidden=T|Text=Y|Name=RoHS
|RECORD=41|OwnerIndex=336|IndexInSheet=22|OwnerPartId=-1|Location.X=318|Location.Y=280|Color=8388608|FontID=7|IsHidden=T|Text=http://www.national.com/pf/DS/DS90LV028AQ.html|Name=ComponentLink2URL
|RECORD=41|OwnerIndex=336|IndexInSheet=23|OwnerPartId=-1|Location.X=318|Location.Y=280|Color=8388608|FontID=1|IsHidden=T|Text=NSZXTT*90LV0*28AQM|Name=PackageTopMarking
|RECORD=41|OwnerIndex=336|IndexInSheet=24|OwnerPartId=-1|Location.X=318|Location.Y=280|Color=8388608|FontID=1|IsHidden=T|Text=SOIC Narrow, 4.9 x 3.9 x 1.45mm, 8 Lead, 1.27mm Pitch|Name=PackageDescription
|RECORD=41|OwnerIndex=336|IndexInSheet=25|OwnerPartId=-1|Location.X=318|Location.Y=280|Color=8388608|FontID=1|IsHidden=T|Text=DS90LV028AQ Web Page|Name=ComponentLink2Description
|RECORD=41|OwnerIndex=336|IndexInSheet=26|OwnerPartId=-1|Location.X=318|Location.Y=280|Color=8388608|FontID=7|IsHidden=T|Text=http://www.national.com/packaging/folders/m08a.html|Name=ComponentLink3URL
|RECORD=41|OwnerIndex=336|IndexInSheet=27|OwnerPartId=-1|Location.X=318|Location.Y=280|Color=8388608|FontID=1|IsHidden=T|Text=Interface IC|Name=CompType
|RECORD=34|OwnerIndex=336|IndexInSheet=-1|OwnerPartId=-1|Location.X=340|Location.Y=280|Color=8388608|FontID=1|Text=U4|Name=Designator|ReadOnlyState=1
|RECORD=41|OwnerIndex=336|IndexInSheet=-1|OwnerPartId=-1|Location.X=340|Location.Y=190|Color=8388608|FontID=1|Text=DS90LV028AQMA|Name=Comment
|RECORD=44|OwnerIndex=336
|RECORD=45|OwnerIndex=375|IndexInSheet=-1|Description=SOIC, 8-Leads, Body 4.9x3.9mm, Pitch 1.27mm, IPC High Density|UseComponentLibrary=T|ModelName=M08A_L|ModelType=PCBLIB|DatafileCount=1|ModelDatafileEntity0=M08A_L|ModelDatafileKind0=PCBLib|IsCurrent=T|DatalinksLocked=T|DatabaseDatalinksLocked=T
|RECORD=46|OwnerIndex=376
|RECORD=48|OwnerIndex=376
|RECORD=41|OwnerIndex=378|IndexInSheet=-1|OwnerPartId=-1|Color=8388608|FontID=1|IsHidden=T|Text=2D|Name=Available Preview Images
|RECORD=45|OwnerIndex=375|IndexInSheet=-1|Description=SOIC, 8-Leads, Body 4.9x3.9mm, Pitch 1.27mm, IPC Low Density|UseComponentLibrary=T|ModelName=M08A_M|ModelType=PCBLIB|DatafileCount=1|ModelDatafileEntity0=M08A_M|ModelDatafileKind0=PCBLib|DatalinksLocked=T|DatabaseDatalinksLocked=T
|RECORD=46|OwnerIndex=380
|RECORD=48|OwnerIndex=380
|RECORD=41|OwnerIndex=382|IndexInSheet=-1|OwnerPartId=-1|Color=8388608|FontID=1|IsHidden=T|Text=2D|Name=Available Preview Images
|RECORD=45|OwnerIndex=375|IndexInSheet=-1|Description=SOIC, 8-Leads, Body 4.9x3.9mm, Pitch 1.27mm, IPC Medium Density|UseComponentLibrary=T|ModelName=M08A_N|ModelType=PCBLIB|DatafileCount=1|ModelDatafileEntity0=M08A_N|ModelDatafileKind0=PCBLib|DatalinksLocked=T|DatabaseDatalinksLocked=T
|RECORD=46|OwnerIndex=384
|RECORD=48|OwnerIndex=384
|RECORD=41|OwnerIndex=386|IndexInSheet=-1|OwnerPartId=-1|Color=8388608|FontID=1|IsHidden=T|Text=2D|Name=Available Preview Images
|RECORD=1|LibReference=RES-2|ComponentDescription=Chip Resistor, 4.7 KOhm, +/- 1%, 0.1 W, -55 to 155 degC, 0603 (1608 Metric), RoHS, Tape and Reel RC0603FR-074K7L|PartCount=2|DisplayModeCount=1|IndexInSheet=38|OwnerPartId=-1|Location.X=1040|Location.Y=200|Orientation=1|CurrentPartId=1|LibraryPath=*|SourceLibraryName=Altium Content Vault|TargetFileName=*|AreaColor=11599871|Color=128|PartIDLocked=T|DesignItemId=CMP-2000-06942-1|AllPinCount=2
|RECORD=2|OwnerIndex=388|OwnerPartId=1|FormalType=1|Electrical=4|PinConglomerate=33|PinLength=10|Location.X=1040|Location.Y=220|Name=2|Designator=2|PinPropagationDelay=0.000000E+000
|RECORD=2|OwnerIndex=388|OwnerPartId=1|FormalType=1|Electrical=4|PinConglomerate=35|PinLength=10|Location.X=1040|Location.Y=200|Name=1|Designator=1|PinPropagationDelay=0.000000E+000
|RECORD=6|OwnerIndex=388|IsNotAccesible=T|IndexInSheet=2|OwnerPartId=1|LineWidth=1|Color=16711680|LocationCount=10|X1=1040|Y1=220|X2=1040|Y2=216|X3=1042|Y3=215|X4=1038|Y4=213|X5=1042|Y5=211|X6=1038|Y6=209|X7=1042|Y7=207|X8=1038|Y8=205|X9=1040|Y9=204|X10=1040|Y10=200
|RECORD=41|OwnerIndex=388|IndexInSheet=3|OwnerPartId=-1|Location.X=1037|Location.Y=232|Color=8388608|FontID=1|IsHidden=T|Text=0603|Name=Package Reference
|RECORD=41|OwnerIndex=388|IndexInSheet=4|OwnerPartId=-1|Location.X=1037|Location.Y=232|Color=8388608|FontID=1|IsHidden=T|Text=RC|Name=Series
|RECORD=41|OwnerIndex=388|IndexInSheet=5|OwnerPartId=-1|Location.X=1037|Location.Y=232|Color=8388608|FontID=1|IsHidden=T|Text=100mW|Name=Power Rating
|RECORD=41|OwnerIndex=388|IndexInSheet=6|OwnerPartId=-1|Location.X=1037|Location.Y=232|Color=8388608|FontID=1|IsHidden=T|Text=Yageo|Name=Manufacturer
|RECORD=41|OwnerIndex=388|IndexInSheet=7|OwnerPartId=-1|Location.X=1037|Location.Y=232|Color=8388608|FontID=1|IsHidden=T|Text=100PPM/C|Name=Temperature Coefficient
|RECORD=41|OwnerIndex=388|IndexInSheet=8|OwnerPartId=-1|Location.X=1037|Location.Y=232|Color=8388608|FontID=1|IsHidden=T|Text=4.7kOhms|Name=Resistance
|RECORD=41|OwnerIndex=388|IndexInSheet=9|OwnerPartId=-1|Location.X=1037|Location.Y=232|Color=8388608|FontID=1|IsHidden=T|Text=Rev. 7, 05/2017|Name=Datasheet Version
|RECORD=41|OwnerIndex=388|IndexInSheet=10|OwnerPartId=-1|Location.X=1037|Location.Y=232|Color=8388608|FontID=1|IsHidden=T|Text=Reel|Name=Packaging
|RECORD=41|OwnerIndex=388|IndexInSheet=11|OwnerPartId=-1|Location.X=1037|Location.Y=232|Color=8388608|FontID=1|IsHidden=T|Text=SMD/SMT|Name=Termination Style
|RECORD=41|OwnerIndex=388|IndexInSheet=12|OwnerPartId=-1|Location.X=1037|Location.Y=232|Color=8388608|FontID=7|IsHidden=T|Text=http://www.yageo.com/documents/recent/PYu-RC_Group_51_RoHS_L_7.pdf|Name=Datasheet URL
|RECORD=41|OwnerIndex=388|IndexInSheet=13|OwnerPartId=-1|Location.X=1037|Location.Y=232|Color=8388608|FontID=7|IsHidden=T|Text=http://www.yageo.com/|Name=Manufacturer URL
|RECORD=41|OwnerIndex=388|IndexInSheet=14|OwnerPartId=-1|Location.X=1037|Location.Y=232|Color=8388608|FontID=1|IsHidden=T|Text=2-Pin Surface Mount Device, Body 1.6 x 0.8 mm|Name=Package Description
|RECORD=41|OwnerIndex=388|IndexInSheet=15|OwnerPartId=-1|Location.X=1037|Location.Y=232|Color=8388608|FontID=1|IsHidden=T|Text=1608|Name=Case Code - mm
|RECORD=41|OwnerIndex=388|IndexInSheet=16|OwnerPartId=-1|Location.X=1037|Location.Y=232|Color=8388608|FontID=1|IsHidden=T|Text=50V|Name=Voltage Rating
|RECORD=41|OwnerIndex=388|IndexInSheet=17|OwnerPartId=-1|Location.X=1037|Location.Y=232|Color=8388608|FontID=1|IsHidden=T|Text=0603|Name=Case Code - in
|RECORD=41|OwnerIndex=388|IndexInSheet=18|OwnerPartId=-1|Location.X=1037|Location.Y=232|Color=8388608|FontID=1|IsHidden=T|Text=SurfaceMount|Name=Mounting Technology
|RECORD=41|OwnerIndex=388|IndexInSheet=19|OwnerPartId=-1|Location.X=1037|Location.Y=232|Color=8388608|FontID=1|IsHidden=T|Text=-55Cto+155C|Name=Operating Temperature Range
|RECORD=41|OwnerIndex=388|IndexInSheet=20|OwnerPartId=-1|Location.X=1037|Location.Y=232|Color=8388608|FontID=1|IsHidden=T|Text=1%|Name=Tolerance
|RECORD=41|OwnerIndex=388|IndexInSheet=21|OwnerPartId=-1|Location.X=1037|Location.Y=232|Color=8388608|FontID=1|IsHidden=T|Text=ThickFilmResistorsGeneralPurpose|Name=Product
|RECORD=34|OwnerIndex=388|IndexInSheet=-1|OwnerPartId=-1|Location.X=1043|Location.Y=211|Color=8388608|FontID=1|Text=R11|Name=Designator|ReadOnlyState=1
|RECORD=41|OwnerIndex=388|IndexInSheet=-1|OwnerPartId=-1|Location.X=1043|Location.Y=201|Color=8388608|FontID=1|Text=4.7K|Name=Comment
|RECORD=44|OwnerIndex=388
|RECORD=45|OwnerIndex=415|IndexInSheet=-1|Description=Chip Resistor, 2-Leads, Body 1.60x0.80mm, IPC High Density|UseComponentLibrary=T|ModelName=RESC1608X55X25LL10T15|ModelType=PCBLIB|DatafileCount=1|ModelDatafileEntity0=RESC1608X55X25LL10T15|ModelDatafileKind0=PCBLib|IsCurrent=T|DatalinksLocked=T|DatabaseDatalinksLocked=T
|RECORD=46|OwnerIndex=416
|RECORD=48|OwnerIndex=416
|RECORD=41|OwnerIndex=418|IndexInSheet=-1|OwnerPartId=-1|Color=8388608|FontID=1|IsHidden=T|Text=2D|Name=Available Preview Images
|RECORD=45|OwnerIndex=415|IndexInSheet=-1|Description=Chip Resistor, 2-Leads, Body 1.70x0.90mm, IPC Low Density|UseComponentLibrary=T|ModelName=RESC1608X55X25ML10T15|ModelType=PCBLIB|DatafileCount=1|ModelDatafileEntity0=RESC1608X55X25ML10T15|ModelDatafileKind0=PCBLib|DatalinksLocked=T|DatabaseDatalinksLocked=T
|RECORD=46|OwnerIndex=420
|RECORD=48|OwnerIndex=420
|RECORD=41|OwnerIndex=422|IndexInSheet=-1|OwnerPartId=-1|Color=8388608|FontID=1|IsHidden=T|Text=2D|Name=Available Preview Images
|RECORD=45|OwnerIndex=415|IndexInSheet=-1|Description=Chip Resistor, 2-Leads, Body 1.70x0.90mm, IPC Medium Density|UseComponentLibrary=T|ModelName=RESC1608X55X25NL10T15|ModelType=PCBLIB|DatafileCount=1|ModelDatafileEntity0=RESC1608X55X25NL10T15|ModelDatafileKind0=PCBLib|DatalinksLocked=T|DatabaseDatalinksLocked=T
|RECORD=46|OwnerIndex=424
|RECORD=48|OwnerIndex=424
|RECORD=41|OwnerIndex=426|IndexInSheet=-1|OwnerPartId=-1|Color=8388608|FontID=1|IsHidden=T|Text=2D|Name=Available Preview Images
|RECORD=1|LibReference=RES-2|ComponentDescription=Chip Resistor, 4.7 KOhm, +/- 1%, 0.1 W, -55 to 155 degC, 0603 (1608 Metric), RoHS, Tape and Reel RC0603FR-074K7L|PartCount=2|DisplayModeCount=1|IndexInSheet=39|OwnerPartId=-1|Location.X=1010|Location.Y=200|Orientation=1|CurrentPartId=1|LibraryPath=*|SourceLibraryName=Altium Content Vault|TargetFileName=*|AreaColor=11599871|Color=128|PartIDLocked=T|DesignItemId=CMP-2000-06942-1|AllPinCount=2
|RECORD=2|OwnerIndex=428|OwnerPartId=1|FormalType=1|Electrical=4|PinConglomerate=33|PinLength=10|Location.X=1010|Location.Y=220|Name=2|Designator=2|PinPropagationDelay=0.000000E+000
|RECORD=2|OwnerIndex=428|OwnerPartId=1|FormalType=1|Electrical=4|PinConglomerate=35|PinLength=10|Location.X=1010|Location.Y=200|Name=1|Designator=1|PinPropagationDelay=0.000000E+000
|RECORD=6|OwnerIndex=428|IsNotAccesible=T|IndexInSheet=2|OwnerPartId=1|LineWidth=1|Color=16711680|LocationCount=10|X1=1010|Y1=220|X2=1010|Y2=216|X3=1012|Y3=215|X4=1008|Y4=213|X5=1012|Y5=211|X6=1008|Y6=209|X7=1012|Y7=207|X8=1008|Y8=205|X9=1010|Y9=204|X10=1010|Y10=200
|RECORD=41|OwnerIndex=428|IndexInSheet=3|OwnerPartId=-1|Location.X=1007|Location.Y=232|Color=8388608|FontID=1|IsHidden=T|Text=0603|Name=Package Reference
|RECORD=41|OwnerIndex=428|IndexInSheet=4|OwnerPartId=-1|Location.X=1007|Location.Y=232|Color=8388608|FontID=1|IsHidden=T|Text=RC|Name=Series
|RECORD=41|OwnerIndex=428|IndexInSheet=5|OwnerPartId=-1|Location.X=1007|Location.Y=232|Color=8388608|FontID=1|IsHidden=T|Text=100mW|Name=Power Rating
|RECORD=41|OwnerIndex=428|IndexInSheet=6|OwnerPartId=-1|Location.X=1007|Location.Y=232|Color=8388608|FontID=1|IsHidden=T|Text=Yageo|Name=Manufacturer
|RECORD=41|OwnerIndex=428|IndexInSheet=7|OwnerPartId=-1|Location.X=1007|Location.Y=232|Color=8388608|FontID=1|IsHidden=T|Text=100PPM/C|Name=Temperature Coefficient
|RECORD=41|OwnerIndex=428|IndexInSheet=8|OwnerPartId=-1|Location.X=1007|Location.Y=232|Color=8388608|FontID=1|IsHidden=T|Text=4.7kOhms|Name=Resistance
|RECORD=41|OwnerIndex=428|IndexInSheet=9|OwnerPartId=-1|Location.X=1007|Location.Y=232|Color=8388608|FontID=1|IsHidden=T|Text=Rev. 7, 05/2017|Name=Datasheet Version
|RECORD=41|OwnerIndex=428|IndexInSheet=10|OwnerPartId=-1|Location.X=1007|Location.Y=232|Color=8388608|FontID=1|IsHidden=T|Text=Reel|Name=Packaging
|RECORD=41|OwnerIndex=428|IndexInSheet=11|OwnerPartId=-1|Location.X=1007|Location.Y=232|Color=8388608|FontID=1|IsHidden=T|Text=SMD/SMT|Name=Termination Style
|RECORD=41|OwnerIndex=428|IndexInSheet=12|OwnerPartId=-1|Location.X=1007|Location.Y=232|Color=8388608|FontID=7|IsHidden=T|Text=http://www.yageo.com/documents/recent/PYu-RC_Group_51_RoHS_L_7.pdf|Name=Datasheet URL
|RECORD=41|OwnerIndex=428|IndexInSheet=13|OwnerPartId=-1|Location.X=1007|Location.Y=232|Color=8388608|FontID=7|IsHidden=T|Text=http://www.yageo.com/|Name=Manufacturer URL
|RECORD=41|OwnerIndex=428|IndexInSheet=14|OwnerPartId=-1|Location.X=1007|Location.Y=232|Color=8388608|FontID=1|IsHidden=T|Text=2-Pin Surface Mount Device, Body 1.6 x 0.8 mm|Name=Package Description
|RECORD=41|OwnerIndex=428|IndexInSheet=15|OwnerPartId=-1|Location.X=1007|Location.Y=232|Color=8388608|FontID=1|IsHidden=T|Text=1608|Name=Case Code - mm
|RECORD=41|OwnerIndex=428|IndexInSheet=16|OwnerPartId=-1|Location.X=1007|Location.Y=232|Color=8388608|FontID=1|IsHidden=T|Text=50V|Name=Voltage Rating
|RECORD=41|OwnerIndex=428|IndexInSheet=17|OwnerPartId=-1|Location.X=1007|Location.Y=232|Color=8388608|FontID=1|IsHidden=T|Text=0603|Name=Case Code - in
|RECORD=41|OwnerIndex=428|IndexInSheet=18|OwnerPartId=-1|Location.X=1007|Location.Y=232|Color=8388608|FontID=1|IsHidden=T|Text=SurfaceMount|Name=Mounting Technology
|RECORD=41|OwnerIndex=428|IndexInSheet=19|OwnerPartId=-1|Location.X=1007|Location.Y=232|Color=8388608|FontID=1|IsHidden=T|Text=-55Cto+155C|Name=Operating Temperature Range
|RECORD=41|OwnerIndex=428|IndexInSheet=20|OwnerPartId=-1|Location.X=1007|Location.Y=232|Color=8388608|FontID=1|IsHidden=T|Text=1%|Name=Tolerance
|RECORD=41|OwnerIndex=428|IndexInSheet=21|OwnerPartId=-1|Location.X=1007|Location.Y=232|Color=8388608|FontID=1|IsHidden=T|Text=ThickFilmResistorsGeneralPurpose|Name=Product
|RECORD=34|OwnerIndex=428|IndexInSheet=-1|OwnerPartId=-1|Location.X=1013|Location.Y=211|Color=8388608|FontID=1|Text=R10|Name=Designator|ReadOnlyState=1
|RECORD=41|OwnerIndex=428|IndexInSheet=-1|OwnerPartId=-1|Location.X=1013|Location.Y=201|Color=8388608|FontID=1|Text=4.7K|Name=Comment
|RECORD=44|OwnerIndex=428
|RECORD=45|OwnerIndex=455|IndexInSheet=-1|Description=Chip Resistor, 2-Leads, Body 1.60x0.80mm, IPC High Density|UseComponentLibrary=T|ModelName=RESC1608X55X25LL10T15|ModelType=PCBLIB|DatafileCount=1|ModelDatafileEntity0=RESC1608X55X25LL10T15|ModelDatafileKind0=PCBLib|IsCurrent=T|DatalinksLocked=T|DatabaseDatalinksLocked=T
|RECORD=46|OwnerIndex=456
|RECORD=48|OwnerIndex=456
|RECORD=41|OwnerIndex=458|IndexInSheet=-1|OwnerPartId=-1|Color=8388608|FontID=1|IsHidden=T|Text=2D|Name=Available Preview Images
|RECORD=45|OwnerIndex=455|IndexInSheet=-1|Description=Chip Resistor, 2-Leads, Body 1.70x0.90mm, IPC Low Density|UseComponentLibrary=T|ModelName=RESC1608X55X25ML10T15|ModelType=PCBLIB|DatafileCount=1|ModelDatafileEntity0=RESC1608X55X25ML10T15|ModelDatafileKind0=PCBLib|DatalinksLocked=T|DatabaseDatalinksLocked=T
|RECORD=46|OwnerIndex=460
|RECORD=48|OwnerIndex=460
|RECORD=41|OwnerIndex=462|IndexInSheet=-1|OwnerPartId=-1|Color=8388608|FontID=1|IsHidden=T|Text=2D|Name=Available Preview Images
|RECORD=45|OwnerIndex=455|IndexInSheet=-1|Description=Chip Resistor, 2-Leads, Body 1.70x0.90mm, IPC Medium Density|UseComponentLibrary=T|ModelName=RESC1608X55X25NL10T15|ModelType=PCBLIB|DatafileCount=1|ModelDatafileEntity0=RESC1608X55X25NL10T15|ModelDatafileKind0=PCBLib|DatalinksLocked=T|DatabaseDatalinksLocked=T
|RECORD=46|OwnerIndex=464
|RECORD=48|OwnerIndex=464
|RECORD=41|OwnerIndex=466|IndexInSheet=-1|OwnerPartId=-1|Color=8388608|FontID=1|IsHidden=T|Text=2D|Name=Available Preview Images
|RECORD=1|LibReference=CAP|ComponentDescription=C0603X104K5RACAUTO|PartCount=2|DisplayModeCount=2|IndexInSheet=40|OwnerPartId=-1|Location.X=1070|Location.Y=200|Orientation=1|CurrentPartId=1|SourceLibraryName=Altium Content Vault|TargetFileName=*|AreaColor=11599871|Color=128|PartIDLocked=F|DesignItemId=CMP-2006-00003-1|AllPinCount=2
|RECORD=2|OwnerIndex=468|OwnerPartId=1|OwnerPartDisplayMode=1|FormalType=1|Electrical=4|PinConglomerate=35|PinLength=10|Location.X=1080|Location.Y=200|Name=1|Designator=1|PinPropagationDelay=0.000000E+000
|RECORD=2|OwnerIndex=468|OwnerPartId=1|OwnerPartDisplayMode=1|FormalType=1|Electrical=4|PinConglomerate=33|PinLength=10|Location.X=1080|Location.Y=210|Name=2|Designator=2|PinPropagationDelay=0.000000E+000
|RECORD=13|OwnerIndex=468|IsNotAccesible=T|IndexInSheet=2|OwnerPartId=1|OwnerPartDisplayMode=1|Location.X=1088|Location.Y=200|Corner.X=1072|Corner.Y=200|LineWidth=1|Color=16711680
|RECORD=13|OwnerIndex=468|IsNotAccesible=T|IndexInSheet=3|OwnerPartId=1|OwnerPartDisplayMode=1|Location.X=1080|Location.Y=204|Corner.X=1080|Corner.Y=210|LineWidth=1|Color=16711680
|RECORD=12|OwnerIndex=468|IsNotAccesible=T|IndexInSheet=4|OwnerPartId=1|OwnerPartDisplayMode=1|Location.X=1080|Location.Y=220|Radius=16|LineWidth=1|StartAngle=241.000|EndAngle=270.000|Color=16711680
|RECORD=12|OwnerIndex=468|IsNotAccesible=T|IndexInSheet=5|OwnerPartId=1|OwnerPartDisplayMode=1|Location.X=1080|Location.Y=220|Radius=16|LineWidth=1|StartAngle=270.000|EndAngle=299.000|Color=16711680
|RECORD=2|OwnerIndex=468|OwnerPartId=1|FormalType=1|Electrical=4|PinConglomerate=35|PinLength=10|Location.X=1080|Location.Y=200|Name=1|Designator=1|PinPropagationDelay=0.000000E+000
|RECORD=2|OwnerIndex=468|OwnerPartId=1|FormalType=1|Electrical=4|PinConglomerate=33|PinLength=10|Location.X=1080|Location.Y=210|Name=2|Designator=2|PinPropagationDelay=0.000000E+000
|RECORD=13|OwnerIndex=468|IsNotAccesible=T|IndexInSheet=8|OwnerPartId=1|Location.X=1072|Location.Y=207|Corner.X=1088|Corner.Y=207|LineWidth=1|Color=16711680
|RECORD=13|OwnerIndex=468|IsNotAccesible=T|IndexInSheet=9|OwnerPartId=1|Location.X=1088|Location.Y=203|Corner.X=1072|Corner.Y=203|LineWidth=1|Color=16711680
|RECORD=6|OwnerIndex=468|IsNotAccesible=T|IndexInSheet=10|OwnerPartId=1|LineWidth=1|Color=16711680|LocationCount=2|X1=1080|Y1=200|X2=1080|Y2=203
|RECORD=6|OwnerIndex=468|IsNotAccesible=T|IndexInSheet=11|OwnerPartId=1|LineWidth=1|Color=16711680|LocationCount=2|X1=1080|Y1=210|X2=1080|Y2=207
|RECORD=41|OwnerIndex=468|IndexInSheet=12|OwnerPartId=-1|Location.X=1071|Location.Y=222|Color=8388608|FontID=1|IsHidden=T|Text=Kemet|Name=Manufacturer
|RECORD=41|OwnerIndex=468|IndexInSheet=13|OwnerPartId=-1|Location.X=1071|Location.Y=222|Color=8388608|FontID=1|IsHidden=T|Text=C0603X104K5RACAUTO|Name=Part Number
|RECORD=34|OwnerIndex=468|IndexInSheet=-1|OwnerPartId=-1|Location.X=1089|Location.Y=201|Color=8388608|FontID=1|Text=C23|Name=Designator|ReadOnlyState=1
|RECORD=41|OwnerIndex=468|IndexInSheet=-1|OwnerPartId=-1|Location.X=1089|Location.Y=191|Color=8388608|FontID=1|Text=0.1uF|Name=Comment
|RECORD=44|OwnerIndex=468
|RECORD=45|OwnerIndex=489|IndexInSheet=-1|Description=Chip Capacitor, 2-Leads, Body 1.60x0.80mm, IPC Low Density|UseComponentLibrary=T|ModelName=CAPC1608X87X45ML20T05|ModelType=PCBLIB|DatafileCount=1|ModelDatafileEntity0=CAPC1608X87X45ML20T05|ModelDatafileKind0=PCBLib|IsCurrent=T|DatalinksLocked=T|DatabaseDatalinksLocked=T
|RECORD=46|OwnerIndex=490
|RECORD=48|OwnerIndex=490
|RECORD=41|OwnerIndex=492|IndexInSheet=-1|OwnerPartId=-1|Color=8388608|FontID=1|Text=2D|Name=Available Preview Images
|RECORD=45|OwnerIndex=489|IndexInSheet=-1|Description=Chip Capacitor, 2-Leads, Body 1.60x0.80mm, IPC High Density|UseComponentLibrary=T|ModelName=CAPC1608X87X45LL20T05|ModelType=PCBLIB|DatafileCount=1|ModelDatafileEntity0=CAPC1608X87X45LL20T05|ModelDatafileKind0=PCBLib|DatalinksLocked=T|DatabaseDatalinksLocked=T
|RECORD=46|OwnerIndex=494
|RECORD=48|OwnerIndex=494
|RECORD=41|OwnerIndex=496|IndexInSheet=-1|OwnerPartId=-1|Color=8388608|FontID=1|Text=2D|Name=Available Preview Images
|RECORD=45|OwnerIndex=489|IndexInSheet=-1|Description=Chip Capacitor, 2-Leads, Body 1.60x0.80mm, IPC Medium Density|UseComponentLibrary=T|ModelName=CAPC1608X87X45NL20T05|ModelType=PCBLIB|DatafileCount=1|ModelDatafileEntity0=CAPC1608X87X45NL20T05|ModelDatafileKind0=PCBLib|DatalinksLocked=T|DatabaseDatalinksLocked=T
|RECORD=46|OwnerIndex=498
|RECORD=48|OwnerIndex=498
|RECORD=41|OwnerIndex=500|IndexInSheet=-1|OwnerPartId=-1|Color=8388608|FontID=1|Text=2D|Name=Available Preview Images
|RECORD=17|IndexInSheet=41|OwnerPartId=-1|Style=4|ShowNetName=T|Location.X=1080|Location.Y=170|Orientation=3|Color=128|FontID=1|Text=GND
|RECORD=17|IndexInSheet=42|OwnerPartId=-1|Style=4|ShowNetName=T|Location.X=1040|Location.Y=170|Orientation=3|Color=128|FontID=1|Text=GND
|RECORD=17|IndexInSheet=43|OwnerPartId=-1|Style=4|ShowNetName=T|Location.X=1010|Location.Y=170|Orientation=3|Color=128|FontID=1|Text=GND
|RECORD=17|IndexInSheet=44|OwnerPartId=-1|ShowNetName=T|Location.X=1080|Location.Y=320|Orientation=1|Color=128|FontID=1|Text=+3.3V
|RECORD=17|IndexInSheet=45|OwnerPartId=-1|ShowNetName=T|Location.X=1280|Location.Y=280|Color=255|FontID=1|Text=MAC_PPS_IN1-|IsCrossSheetConnector=T
|RECORD=17|IndexInSheet=46|OwnerPartId=-1|ShowNetName=T|Location.X=1280|Location.Y=290|Color=255|FontID=1|Text=MAC_PPS_IN1+|IsCrossSheetConnector=T
|RECORD=17|IndexInSheet=47|OwnerPartId=-1|ShowNetName=T|Location.X=1280|Location.Y=250|Color=255|FontID=1|Text=MAC_PPS_IN0-|IsCrossSheetConnector=T
|RECORD=17|IndexInSheet=48|OwnerPartId=-1|ShowNetName=T|Location.X=1280|Location.Y=260|Color=255|FontID=1|Text=MAC_PPS_IN0+|IsCrossSheetConnector=T
|RECORD=17|IndexInSheet=49|OwnerPartId=-1|Style=4|ShowNetName=T|Location.X=1260|Location.Y=170|Orientation=3|Color=128|FontID=1|Text=GND
|RECORD=17|IndexInSheet=50|OwnerPartId=-1|ShowNetName=T|Location.X=420|Location.Y=650|Orientation=2|Color=255|FontID=1|Text=MAC_PPS_IN1-|IsCrossSheetConnector=T
|RECORD=17|IndexInSheet=51|OwnerPartId=-1|ShowNetName=T|Location.X=420|Location.Y=660|Orientation=2|Color=255|FontID=1|Text=MAC_PPS_IN1+|IsCrossSheetConnector=T
|RECORD=17|IndexInSheet=52|OwnerPartId=-1|ShowNetName=T|Location.X=420|Location.Y=630|Orientation=2|Color=255|FontID=1|Text=MAC_PPS_IN0-|IsCrossSheetConnector=T
|RECORD=17|IndexInSheet=53|OwnerPartId=-1|ShowNetName=T|Location.X=420|Location.Y=640|Orientation=2|Color=255|FontID=1|Text=MAC_PPS_IN0+|IsCrossSheetConnector=T
|RECORD=1|LibReference=RES|PartCount=2|DisplayModeCount=2|IndexInSheet=54|OwnerPartId=-1|Location.X=220|Location.Y=270|Orientation=1|CurrentPartId=1|SourceLibraryName=Altium Content Vault|TargetFileName=*|AreaColor=11599871|Color=128|PartIDLocked=F|DesignItemId=CMP-2000-03854-1|AllPinCount=2
|RECORD=2|OwnerIndex=515|OwnerPartId=1|OwnerPartDisplayMode=1|FormalType=1|Electrical=4|PinConglomerate=33|PinLength=10|Location.X=230|Location.Y=290|Name=2|Designator=2|PinPropagationDelay=0.000000E+000
|RECORD=2|OwnerIndex=515|OwnerPartId=1|OwnerPartDisplayMode=1|FormalType=1|Electrical=4|PinConglomerate=35|PinLength=10|Location.X=230|Location.Y=270|Name=1|Designator=1|PinPropagationDelay=0.000000E+000
|RECORD=14|OwnerIndex=515|IsNotAccesible=T|IndexInSheet=2|OwnerPartId=1|OwnerPartDisplayMode=1|Location.X=226|Location.Y=270|Corner.X=234|Corner.Y=290|LineWidth=1|Color=16711680|AreaColor=11599871
|RECORD=2|OwnerIndex=515|OwnerPartId=1|FormalType=1|Electrical=4|PinConglomerate=33|PinLength=10|Location.X=230|Location.Y=290|Name=2|Designator=2|PinPropagationDelay=0.000000E+000
|RECORD=2|OwnerIndex=515|OwnerPartId=1|FormalType=1|Electrical=4|PinConglomerate=35|PinLength=10|Location.X=230|Location.Y=270|Name=1|Designator=1|PinPropagationDelay=0.000000E+000
|RECORD=6|OwnerIndex=515|IsNotAccesible=T|IndexInSheet=5|OwnerPartId=1|LineWidth=1|Color=16711680|LocationCount=10|X1=230|Y1=290|X2=230|Y2=286|X3=232|Y3=285|X4=228|Y4=283|X5=232|Y5=281|X6=228|Y6=279|X7=232|Y7=277|X8=228|Y8=275|X9=230|Y9=274|X10=230|Y10=270
|RECORD=41|OwnerIndex=515|IndexInSheet=6|OwnerPartId=-1|Location.X=227|Location.Y=302|Color=8388608|FontID=1|IsHidden=T|Text=CRCW0603110RFKEA|Name=Part Number
|RECORD=41|OwnerIndex=515|IndexInSheet=7|OwnerPartId=-1|Location.X=227|Location.Y=302|Color=8388608|FontID=1|IsHidden=T|Text=Vishay Dale|Name=Manufacturer
|RECORD=34|OwnerIndex=515|IndexInSheet=-1|OwnerPartId=-1|Location.X=233|Location.Y=281|Color=8388608|FontID=1|Text=R12|Name=Designator|ReadOnlyState=1
|RECORD=41|OwnerIndex=515|IndexInSheet=-1|OwnerPartId=-1|Location.X=233|Location.Y=271|Color=8388608|FontID=1|Text=110R|Name=Comment
|RECORD=44|OwnerIndex=515
|RECORD=45|OwnerIndex=530|IndexInSheet=-1|Description=Chip Resistor, 2-Leads, Body 1.55x0.85mm, IPC Medium Density|UseComponentLibrary=T|ModelName=RESC1609X50X30NL10T20|ModelType=PCBLIB|DatafileCount=1|ModelDatafileEntity0=RESC1609X50X30NL10T20|ModelDatafileKind0=PCBLib|IsCurrent=T|DatalinksLocked=T|DatabaseDatalinksLocked=T
|RECORD=46|OwnerIndex=531
|RECORD=48|OwnerIndex=531
|RECORD=41|OwnerIndex=533|IndexInSheet=-1|OwnerPartId=-1|Color=8388608|FontID=1|IsHidden=T|Text=2D|Name=Available Preview Images
|RECORD=45|OwnerIndex=530|IndexInSheet=-1|Description=Chip Resistor, 2-Leads, Body 1.55x0.85mm, IPC High Density|UseComponentLibrary=T|ModelName=RESC1609X50X30LL10T20|ModelType=PCBLIB|DatafileCount=1|ModelDatafileEntity0=RESC1609X50X30LL10T20|ModelDatafileKind0=PCBLib|DatalinksLocked=T|DatabaseDatalinksLocked=T
|RECORD=46|OwnerIndex=535
|RECORD=48|OwnerIndex=535
|RECORD=41|OwnerIndex=537|IndexInSheet=-1|OwnerPartId=-1|Color=8388608|FontID=1|IsHidden=T|Text=2D|Name=Available Preview Images
|RECORD=45|OwnerIndex=530|IndexInSheet=-1|Description=Chip Resistor, 2-Leads, Body 1.55x0.85mm, IPC Low Density|UseComponentLibrary=T|ModelName=RESC1609X50X30ML10T20|ModelType=PCBLIB|DatafileCount=1|ModelDatafileEntity0=RESC1609X50X30ML10T20|ModelDatafileKind0=PCBLib|DatalinksLocked=T|DatabaseDatalinksLocked=T
|RECORD=46|OwnerIndex=539
|RECORD=48|OwnerIndex=539
|RECORD=41|OwnerIndex=541|IndexInSheet=-1|OwnerPartId=-1|Color=8388608|FontID=1|IsHidden=T|Text=2D|Name=Available Preview Images
|RECORD=1|LibReference=CAP|ComponentDescription=C0603X104K5RACAUTO|PartCount=2|DisplayModeCount=2|IndexInSheet=55|OwnerPartId=-1|Location.X=300|Location.Y=180|Orientation=3|CurrentPartId=1|SourceLibraryName=Altium Content Vault|TargetFileName=*|AreaColor=11599871|Color=128|PartIDLocked=F|DesignItemId=CMP-2006-00003-1|AllPinCount=2
|RECORD=2|OwnerIndex=543|OwnerPartId=1|OwnerPartDisplayMode=1|FormalType=1|Electrical=4|PinConglomerate=33|PinLength=10|Location.X=290|Location.Y=180|Name=1|Designator=1|PinPropagationDelay=0.000000E+000
|RECORD=2|OwnerIndex=543|OwnerPartId=1|OwnerPartDisplayMode=1|FormalType=1|Electrical=4|PinConglomerate=35|PinLength=10|Location.X=290|Location.Y=170|Name=2|Designator=2|PinPropagationDelay=0.000000E+000
|RECORD=13|OwnerIndex=543|IsNotAccesible=T|IndexInSheet=2|OwnerPartId=1|OwnerPartDisplayMode=1|Location.X=282|Location.Y=180|Corner.X=298|Corner.Y=180|LineWidth=1|Color=16711680
|RECORD=13|OwnerIndex=543|IsNotAccesible=T|IndexInSheet=3|OwnerPartId=1|OwnerPartDisplayMode=1|Location.X=290|Location.Y=176|Corner.X=290|Corner.Y=170|LineWidth=1|Color=16711680
|RECORD=12|OwnerIndex=543|IsNotAccesible=T|IndexInSheet=4|OwnerPartId=1|OwnerPartDisplayMode=1|Location.X=290|Location.Y=160|Radius=16|LineWidth=1|StartAngle=61.000|EndAngle=90.000|Color=16711680
|RECORD=12|OwnerIndex=543|IsNotAccesible=T|IndexInSheet=5|OwnerPartId=1|OwnerPartDisplayMode=1|Location.X=290|Location.Y=160|Radius=16|LineWidth=1|StartAngle=90.000|EndAngle=119.000|Color=16711680
|RECORD=2|OwnerIndex=543|OwnerPartId=1|FormalType=1|Electrical=4|PinConglomerate=33|PinLength=10|Location.X=290|Location.Y=180|Name=1|Designator=1|PinPropagationDelay=0.000000E+000
|RECORD=2|OwnerIndex=543|OwnerPartId=1|FormalType=1|Electrical=4|PinConglomerate=35|PinLength=10|Location.X=290|Location.Y=170|Name=2|Designator=2|PinPropagationDelay=0.000000E+000
|RECORD=13|OwnerIndex=543|IsNotAccesible=T|IndexInSheet=8|OwnerPartId=1|Location.X=298|Location.Y=173|Corner.X=282|Corner.Y=173|LineWidth=1|Color=16711680
|RECORD=13|OwnerIndex=543|IsNotAccesible=T|IndexInSheet=9|OwnerPartId=1|Location.X=282|Location.Y=177|Corner.X=298|Corner.Y=177|LineWidth=1|Color=16711680
|RECORD=6|OwnerIndex=543|IsNotAccesible=T|IndexInSheet=10|OwnerPartId=1|LineWidth=1|Color=16711680|LocationCount=2|X1=290|Y1=180|X2=290|Y2=177
|RECORD=6|OwnerIndex=543|IsNotAccesible=T|IndexInSheet=11|OwnerPartId=1|LineWidth=1|Color=16711680|LocationCount=2|X1=290|Y1=170|X2=290|Y2=173
|RECORD=41|OwnerIndex=543|IndexInSheet=12|OwnerPartId=-1|Location.X=281|Location.Y=192|Color=8388608|FontID=1|IsHidden=T|Text=Kemet|Name=Manufacturer
|RECORD=41|OwnerIndex=543|IndexInSheet=13|OwnerPartId=-1|Location.X=281|Location.Y=192|Color=8388608|FontID=1|IsHidden=T|Text=C0603X104K5RACAUTO|Name=Part Number
|RECORD=34|OwnerIndex=543|IndexInSheet=-1|OwnerPartId=-1|Location.X=299|Location.Y=167|Color=8388608|FontID=1|Text=C24|Name=Designator|ReadOnlyState=1
|RECORD=41|OwnerIndex=543|IndexInSheet=-1|OwnerPartId=-1|Location.X=299|Location.Y=153|Color=8388608|FontID=1|Text=0.1uF|Name=Comment
|RECORD=44|OwnerIndex=543
|RECORD=45|OwnerIndex=564|IndexInSheet=-1|Description=Chip Capacitor, 2-Leads, Body 1.60x0.80mm, IPC Low Density|UseComponentLibrary=T|ModelName=CAPC1608X87X45ML20T05|ModelType=PCBLIB|DatafileCount=1|ModelDatafileEntity0=CAPC1608X87X45ML20T05|ModelDatafileKind0=PCBLib|IsCurrent=T|DatalinksLocked=T|DatabaseDatalinksLocked=T
|RECORD=46|OwnerIndex=565
|RECORD=48|OwnerIndex=565
|RECORD=41|OwnerIndex=567|IndexInSheet=-1|OwnerPartId=-1|Color=8388608|FontID=1|Text=2D|Name=Available Preview Images
|RECORD=45|OwnerIndex=564|IndexInSheet=-1|Description=Chip Capacitor, 2-Leads, Body 1.60x0.80mm, IPC High Density|UseComponentLibrary=T|ModelName=CAPC1608X87X45LL20T05|ModelType=PCBLIB|DatafileCount=1|ModelDatafileEntity0=CAPC1608X87X45LL20T05|ModelDatafileKind0=PCBLib|DatalinksLocked=T|DatabaseDatalinksLocked=T
|RECORD=46|OwnerIndex=569
|RECORD=48|OwnerIndex=569
|RECORD=41|OwnerIndex=571|IndexInSheet=-1|OwnerPartId=-1|Color=8388608|FontID=1|Text=2D|Name=Available Preview Images
|RECORD=45|OwnerIndex=564|IndexInSheet=-1|Description=Chip Capacitor, 2-Leads, Body 1.60x0.80mm, IPC Medium Density|UseComponentLibrary=T|ModelName=CAPC1608X87X45NL20T05|ModelType=PCBLIB|DatafileCount=1|ModelDatafileEntity0=CAPC1608X87X45NL20T05|ModelDatafileKind0=PCBLib|DatalinksLocked=T|DatabaseDatalinksLocked=T
|RECORD=46|OwnerIndex=573
|RECORD=48|OwnerIndex=573
|RECORD=41|OwnerIndex=575|IndexInSheet=-1|OwnerPartId=-1|Color=8388608|FontID=1|Text=2D|Name=Available Preview Images
|RECORD=17|IndexInSheet=56|OwnerPartId=-1|ShowNetName=T|Location.X=290|Location.Y=330|Orientation=1|Color=128|FontID=1|Text=+3.3V
|RECORD=17|IndexInSheet=57|OwnerPartId=-1|Style=4|ShowNetName=T|Location.X=290|Location.Y=130|Orientation=3|Color=128|FontID=1|Text=GND
|RECORD=17|IndexInSheet=58|OwnerPartId=-1|Style=4|ShowNetName=T|Location.X=480|Location.Y=130|Orientation=3|Color=128|FontID=1|Text=GND
|RECORD=22|IndexInSheet=59|OwnerPartId=-1|Location.X=320|Location.Y=240|Color=255|Orientation=1|Symbol=Thin Cross|IsActive=T|SuppressAll=T
|RECORD=22|IndexInSheet=60|OwnerPartId=-1|Location.X=320|Location.Y=230|Color=255|Orientation=1|Symbol=Thin Cross|IsActive=T|SuppressAll=T
|RECORD=22|IndexInSheet=61|OwnerPartId=-1|Location.X=440|Location.Y=240|Color=255|Orientation=1|Symbol=Thin Cross|IsActive=T|SuppressAll=T
|RECORD=17|IndexInSheet=62|OwnerPartId=-1|Style=1|ShowNetName=T|Location.X=580|Location.Y=270|Color=255|FontID=1|Text=FPGA_MAC_PPSDIFF_OUT|IsCrossSheetConnector=T
|RECORD=17|IndexInSheet=63|OwnerPartId=-1|ShowNetName=T|Location.X=1040|Location.Y=620|Color=255|FontID=1|Text=MAC_PPS_OUT+|IsCrossSheetConnector=T
|RECORD=17|IndexInSheet=64|OwnerPartId=-1|ShowNetName=T|Location.X=1040|Location.Y=610|Color=255|FontID=1|Text=MAC_PPS_OUT-|IsCrossSheetConnector=T
|RECORD=17|IndexInSheet=65|OwnerPartId=-1|ShowNetName=T|Location.X=970|Location.Y=290|Orientation=2|Color=255|FontID=1|Text=FPGA_MAC_PPS_IN1-|IsCrossSheetConnector=T
|RECORD=41|IndexInSheet=66|OwnerPartId=-1|Color=8388608|FontID=1|IsHidden=T|Text=*|Name=CurrentTime|ReadOnlyState=1
|RECORD=41|IndexInSheet=67|OwnerPartId=-1|Color=8388608|FontID=1|IsHidden=T|Text=*|Name=CurrentDate|ReadOnlyState=1
|RECORD=41|IndexInSheet=68|OwnerPartId=-1|Color=8388608|FontID=1|IsHidden=T|Text=*|Name=Time|ReadOnlyState=1
|RECORD=41|IndexInSheet=69|OwnerPartId=-1|Color=8388608|FontID=1|IsHidden=T|Text=*|Name=Date|ReadOnlyState=1
|RECORD=41|IndexInSheet=70|OwnerPartId=-1|Color=8388608|FontID=1|IsHidden=T|Text=*|Name=DocumentFullPathAndName|ReadOnlyState=1
|RECORD=41|IndexInSheet=71|OwnerPartId=-1|Color=8388608|FontID=1|IsHidden=T|Text=*|Name=DocumentName|ReadOnlyState=1
|RECORD=41|IndexInSheet=72|OwnerPartId=-1|Color=8388608|FontID=1|IsHidden=T|Text=*|Name=ModifiedDate|ReadOnlyState=1
|RECORD=41|IndexInSheet=73|OwnerPartId=-1|Color=8388608|FontID=1|IsHidden=T|Text=*|Name=ApprovedBy|ReadOnlyState=1
|RECORD=41|IndexInSheet=74|OwnerPartId=-1|Color=8388608|FontID=1|IsHidden=T|Text=*|Name=CheckedBy|ReadOnlyState=1
|RECORD=41|IndexInSheet=75|OwnerPartId=-1|Color=8388608|FontID=1|IsHidden=T|Text=*|Name=Author|ReadOnlyState=1
|RECORD=41|IndexInSheet=76|OwnerPartId=-1|Color=8388608|FontID=1|IsHidden=T|Text=*|Name=CompanyName|ReadOnlyState=1
|RECORD=41|IndexInSheet=77|OwnerPartId=-1|Color=8388608|FontID=1|IsHidden=T|Text=*|Name=DrawnBy|ReadOnlyState=1
|RECORD=41|IndexInSheet=78|OwnerPartId=-1|Color=8388608|FontID=1|IsHidden=T|Text=*|Name=Engineer|ReadOnlyState=1
|RECORD=41|IndexInSheet=79|OwnerPartId=-1|Color=8388608|FontID=1|IsHidden=T|Text=*|Name=Organization|ReadOnlyState=1
|RECORD=41|IndexInSheet=80|OwnerPartId=-1|Color=8388608|FontID=1|IsHidden=T|Text=*|Name=Address1|ReadOnlyState=1
|RECORD=41|IndexInSheet=81|OwnerPartId=-1|Color=8388608|FontID=1|IsHidden=T|Text=*|Name=Address2|ReadOnlyState=1
|RECORD=41|IndexInSheet=82|OwnerPartId=-1|Color=8388608|FontID=1|IsHidden=T|Text=*|Name=Address3|ReadOnlyState=1
|RECORD=41|IndexInSheet=83|OwnerPartId=-1|Color=8388608|FontID=1|IsHidden=T|Text=*|Name=Address4|ReadOnlyState=1
|RECORD=41|IndexInSheet=84|OwnerPartId=-1|Color=8388608|FontID=1|IsHidden=T|Text=*|Name=Title|ReadOnlyState=1
|RECORD=41|IndexInSheet=85|OwnerPartId=-1|Color=8388608|FontID=1|IsHidden=T|Text=*|Name=DocumentNumber|ReadOnlyState=1
|RECORD=41|IndexInSheet=86|OwnerPartId=-1|Color=8388608|FontID=1|IsHidden=T|Text=*|Name=Revision|ReadOnlyState=1
|RECORD=41|IndexInSheet=87|OwnerPartId=-1|Color=8388608|FontID=1|IsHidden=T|Text=*|Name=SheetNumber|ReadOnlyState=1
|RECORD=41|IndexInSheet=88|OwnerPartId=-1|Color=8388608|FontID=1|IsHidden=T|Text=*|Name=SheetTotal|ReadOnlyState=1
|RECORD=41|IndexInSheet=89|OwnerPartId=-1|Color=8388608|FontID=1|IsHidden=T|Text=*|Name=Rule|ReadOnlyState=1
|RECORD=41|IndexInSheet=90|OwnerPartId=-1|Color=8388608|FontID=1|IsHidden=T|Text=*|Name=ImagePath|ReadOnlyState=1
|RECORD=41|IndexInSheet=91|OwnerPartId=-1|Color=8388608|FontID=1|IsHidden=T|Text=*|Name=ProjectName|ReadOnlyState=1
|RECORD=41|IndexInSheet=92|OwnerPartId=-1|Color=8388608|FontID=1|IsHidden=T|Text=*|Name=Application_BuildNumber|ReadOnlyState=1
|RECORD=17|IndexInSheet=93|OwnerPartId=-1|ShowNetName=T|Location.X=940|Location.Y=890|Color=255|FontID=1|Text=MAC_PPS_IN|IsCrossSheetConnector=T
|RECORD=17|IndexInSheet=94|OwnerPartId=-1|Style=1|ShowNetName=T|Location.X=940|Location.Y=880|Color=255|FontID=1|Text=MAC_PPS_OUT|IsCrossSheetConnector=T
|RECORD=1|LibReference=SA53_Header|PartCount=2|DisplayModeCount=1|IndexInSheet=95|OwnerPartId=-1|Location.X=660|Location.Y=350|CurrentPartId=1|LibraryPath=*|SourceLibraryName=FPGA_CONN.SchLib|TargetFileName=*|AreaColor=11599871|Color=128|PartIDLocked=T|DesignItemId=SA53_Header|AllPinCount=20
|RECORD=41|OwnerIndex=616|OwnerPartId=-1|Location.X=628|Location.Y=480|Color=8388608|FontID=1|IsHidden=T|Text=Digi-Key|Name=Supplier 1|ReadOnlyState=3
|RECORD=14|OwnerIndex=616|IsNotAccesible=T|IndexInSheet=1|OwnerPartId=1|Location.X=660|Location.Y=350|Corner.X=760|Corner.Y=480|Color=128|AreaColor=11599871|IsSolid=T
|RECORD=2|OwnerIndex=616|OwnerPartId=1|FormalType=1|Electrical=4|PinConglomerate=58|PinLength=30|Location.X=660|Location.Y=470|Name=1|Designator=1|SwapIDPart=Ž&Ž||PinPropagationDelay=0.000000E+000
|RECORD=2|OwnerIndex=616|OwnerPartId=1|FormalType=1|Electrical=4|PinConglomerate=58|PinLength=30|Location.X=660|Location.Y=460|Name=3|Designator=3|SwapIDPart=Ž&Ž||PinPropagationDelay=0.000000E+000
|RECORD=2|OwnerIndex=616|OwnerPartId=1|FormalType=1|Electrical=4|PinConglomerate=58|PinLength=30|Location.X=660|Location.Y=450|Name=5|Designator=5|SwapIDPart=Ž&Ž||PinPropagationDelay=0.000000E+000
|RECORD=2|OwnerIndex=616|OwnerPartId=1|FormalType=1|Electrical=4|PinConglomerate=58|PinLength=30|Location.X=660|Location.Y=440|Name=7|Designator=7|SwapIDPart=Ž&Ž||PinPropagationDelay=0.000000E+000
|RECORD=2|OwnerIndex=616|OwnerPartId=1|FormalType=1|Electrical=4|PinConglomerate=58|PinLength=30|Location.X=660|Location.Y=420|Name=10|Designator=10|SwapIDPart=Ž&Ž||PinPropagationDelay=0.000000E+000
|RECORD=2|OwnerIndex=616|OwnerPartId=1|FormalType=1|Electrical=4|PinConglomerate=58|PinLength=30|Location.X=660|Location.Y=410|Name=11|Designator=11|SwapIDPart=Ž&Ž||PinPropagationDelay=0.000000E+000
|RECORD=2|OwnerIndex=616|OwnerPartId=1|FormalType=1|Electrical=4|PinConglomerate=58|PinLength=30|Location.X=660|Location.Y=400|Name=12|Designator=12|SwapIDPart=Ž&Ž||PinPropagationDelay=0.000000E+000
|RECORD=2|OwnerIndex=616|OwnerPartId=1|FormalType=1|Electrical=4|PinConglomerate=58|PinLength=30|Location.X=660|Location.Y=390|Name=13|Designator=13|SwapIDPart=Ž&Ž||PinPropagationDelay=0.000000E+000
|RECORD=2|OwnerIndex=616|OwnerPartId=1|FormalType=1|Electrical=4|PinConglomerate=58|PinLength=30|Location.X=660|Location.Y=380|Name=14|Designator=14|SwapIDPart=Ž&Ž||PinPropagationDelay=0.000000E+000
|RECORD=2|OwnerIndex=616|OwnerPartId=1|FormalType=1|Electrical=4|PinConglomerate=58|PinLength=30|Location.X=660|Location.Y=370|Name=16|Designator=16|SwapIDPart=Ž&Ž||PinPropagationDelay=0.000000E+000
|RECORD=2|OwnerIndex=616|OwnerPartId=1|FormalType=1|Electrical=4|PinConglomerate=58|PinLength=30|Location.X=660|Location.Y=360|Name=18|Designator=18|SwapIDPart=Ž&Ž||PinPropagationDelay=0.000000E+000
|RECORD=41|OwnerIndex=616|IndexInSheet=13|OwnerPartId=-1|Location.X=660|Location.Y=330|Color=8388608|FontID=1|Text=WM24007CT-ND|Name=Supplier Part Number 1|ReadOnlyState=3
|RECORD=2|OwnerIndex=616|OwnerPartId=1|FormalType=1|Electrical=4|PinConglomerate=56|PinLength=30|Location.X=760|Location.Y=470|Name=2|Designator=2|SwapIDPart=Ž&Ž||PinPropagationDelay=0.000000E+000
|RECORD=2|OwnerIndex=616|OwnerPartId=1|FormalType=1|Electrical=4|PinConglomerate=56|PinLength=30|Location.X=760|Location.Y=460|Name=4|Designator=4|SwapIDPart=Ž&Ž||PinPropagationDelay=0.000000E+000
|RECORD=2|OwnerIndex=616|OwnerPartId=1|FormalType=1|Electrical=4|PinConglomerate=56|PinLength=30|Location.X=760|Location.Y=450|Name=6|Designator=6|SwapIDPart=Ž&Ž||PinPropagationDelay=0.000000E+000
|RECORD=2|OwnerIndex=616|OwnerPartId=1|FormalType=1|Electrical=4|PinConglomerate=56|PinLength=30|Location.X=760|Location.Y=430|Name=17|Designator=17|SwapIDPart=Ž&Ž||PinPropagationDelay=0.000000E+000
|RECORD=2|OwnerIndex=616|OwnerPartId=1|FormalType=1|Electrical=4|PinConglomerate=56|PinLength=30|Location.X=760|Location.Y=420|Name=19|Designator=19|SwapIDPart=Ž&Ž||PinPropagationDelay=0.000000E+000
|RECORD=2|OwnerIndex=616|OwnerPartId=1|FormalType=1|Electrical=4|PinConglomerate=56|PinLength=30|Location.X=760|Location.Y=400|Name=20|Designator=20|SwapIDPart=Ž&Ž||PinPropagationDelay=0.000000E+000
|RECORD=2|OwnerIndex=616|OwnerPartId=1|FormalType=1|Electrical=4|PinConglomerate=56|PinLength=30|Location.X=760|Location.Y=380|Name=8|Designator=8|SwapIDPart=Ž&Ž||PinPropagationDelay=0.000000E+000
|RECORD=2|OwnerIndex=616|OwnerPartId=1|FormalType=1|Electrical=4|PinConglomerate=56|PinLength=30|Location.X=760|Location.Y=370|Name=9|Designator=9|SwapIDPart=Ž&Ž||PinPropagationDelay=0.000000E+000
|RECORD=2|OwnerIndex=616|OwnerPartId=1|FormalType=1|Electrical=4|PinConglomerate=56|PinLength=30|Location.X=760|Location.Y=360|Name=15|Designator=15|SwapIDPart=Ž&Ž||PinPropagationDelay=0.000000E+000
|RECORD=34|OwnerIndex=616|IndexInSheet=-1|OwnerPartId=-1|Location.X=660|Location.Y=480|Color=8388608|FontID=1|Text=J31|Name=Designator|ReadOnlyState=1
|RECORD=41|OwnerIndex=616|IndexInSheet=-1|OwnerPartId=-1|Location.X=660|Location.Y=340|Color=8388608|FontID=1|Text=SA53_Header|Name=Comment
|RECORD=44|OwnerIndex=616
|RECORD=45|OwnerIndex=662|IndexInSheet=-1|ModelName=SA53_Header|ModelType=PCBLIB|DatafileCount=1|ModelDatafileEntity0=SA53_Header|ModelDatafileKind0=PCBLib|IsCurrent=T
|RECORD=46|OwnerIndex=663
|RECORD=48|OwnerIndex=663
|RECORD=22|IndexInSheet=96|OwnerPartId=-1|Location.X=630|Location.Y=420|Color=255|Orientation=1|Symbol=Thin Cross|IsActive=T|SuppressAll=T
|RECORD=22|IndexInSheet=97|OwnerPartId=-1|Location.X=630|Location.Y=410|Color=255|Orientation=1|Symbol=Thin Cross|IsActive=T|SuppressAll=T
|RECORD=22|IndexInSheet=98|OwnerPartId=-1|Location.X=630|Location.Y=400|Color=255|Orientation=1|Symbol=Thin Cross|IsActive=T|SuppressAll=T
|RECORD=22|IndexInSheet=99|OwnerPartId=-1|Location.X=630|Location.Y=390|Color=255|Orientation=1|Symbol=Thin Cross|IsActive=T|SuppressAll=T
|RECORD=22|IndexInSheet=100|OwnerPartId=-1|Location.X=630|Location.Y=380|Color=255|Orientation=1|Symbol=Thin Cross|IsActive=T|SuppressAll=T
|RECORD=22|IndexInSheet=101|OwnerPartId=-1|Location.X=630|Location.Y=370|Color=255|Orientation=1|Symbol=Thin Cross|IsActive=T|SuppressAll=T
|RECORD=22|IndexInSheet=102|OwnerPartId=-1|Location.X=630|Location.Y=360|Color=255|Orientation=1|Symbol=Thin Cross|IsActive=T|SuppressAll=T
|RECORD=17|IndexInSheet=103|OwnerPartId=-1|Style=4|ShowNetName=T|Location.X=800|Location.Y=350|Orientation=3|Color=128|FontID=1|Text=GND
|RECORD=1|LibReference=RES|PartCount=2|DisplayModeCount=2|IndexInSheet=104|OwnerPartId=-1|Location.X=1350|Location.Y=950|CurrentPartId=1|SourceLibraryName=Altium Content Vault|TargetFileName=*|AreaColor=11599871|Color=128|PartIDLocked=F|DesignItemId=CMP-2003-04873-1|AllPinCount=2
|RECORD=2|OwnerIndex=674|OwnerPartId=1|OwnerPartDisplayMode=1|FormalType=1|Electrical=4|PinConglomerate=32|PinLength=10|Location.X=1370|Location.Y=940|Name=2|Designator=2|PinPropagationDelay=0.000000E+000
|RECORD=2|OwnerIndex=674|OwnerPartId=1|OwnerPartDisplayMode=1|FormalType=1|Electrical=4|PinConglomerate=34|PinLength=10|Location.X=1350|Location.Y=940|Name=1|Designator=1|PinPropagationDelay=0.000000E+000
|RECORD=14|OwnerIndex=674|IsNotAccesible=T|IndexInSheet=2|OwnerPartId=1|OwnerPartDisplayMode=1|Location.X=1350|Location.Y=936|Corner.X=1370|Corner.Y=944|LineWidth=1|Color=16711680|AreaColor=11599871
|RECORD=2|OwnerIndex=674|OwnerPartId=1|FormalType=1|Electrical=4|PinConglomerate=32|PinLength=10|Location.X=1370|Location.Y=940|Name=2|Designator=2|PinPropagationDelay=0.000000E+000
|RECORD=2|OwnerIndex=674|OwnerPartId=1|FormalType=1|Electrical=4|PinConglomerate=34|PinLength=10|Location.X=1350|Location.Y=940|Name=1|Designator=1|PinPropagationDelay=0.000000E+000
|RECORD=6|OwnerIndex=674|IsNotAccesible=T|IndexInSheet=5|OwnerPartId=1|LineWidth=1|Color=16711680|LocationCount=10|X1=1370|Y1=940|X2=1366|Y2=940|X3=1365|Y3=938|X4=1363|Y4=942|X5=1361|Y5=938|X6=1359|Y6=942|X7=1357|Y7=938|X8=1355|Y8=942|X9=1354|Y9=940|X10=1350|Y10=940
|RECORD=41|OwnerIndex=674|IndexInSheet=6|OwnerPartId=-1|Location.X=1338|Location.Y=953|Color=8388608|FontID=1|IsHidden=T|Text=CRCW12060000Z0EAHP|Name=Part Number
|RECORD=41|OwnerIndex=674|IndexInSheet=7|OwnerPartId=-1|Location.X=1338|Location.Y=953|Color=8388608|FontID=1|IsHidden=T|Text=Vishay Dale|Name=Manufacturer
|RECORD=34|OwnerIndex=674|IndexInSheet=-1|OwnerPartId=-1|Location.X=1349|Location.Y=943|Color=8388608|FontID=1|Text=R45|Name=Designator|ReadOnlyState=1
|RECORD=41|OwnerIndex=674|IndexInSheet=-1|OwnerPartId=-1|Location.X=1349|Location.Y=927|Color=8388608|FontID=1|Text=0_5%_1206|Name=Comment
|RECORD=44|OwnerIndex=674
|RECORD=45|OwnerIndex=689|IndexInSheet=-1|Description=Chip Resistor, 2-Leads, Body 3.10x1.60mm, IPC Low Density|UseComponentLibrary=T|ModelName=RESC3116X65X50ML20T20|ModelType=PCBLIB|DatafileCount=1|ModelDatafileEntity0=RESC3116X65X50ML20T20|ModelDatafileKind0=PCBLib|IsCurrent=T|DatalinksLocked=T|DatabaseDatalinksLocked=T
|RECORD=46|OwnerIndex=690
|RECORD=48|OwnerIndex=690
|RECORD=41|OwnerIndex=692|IndexInSheet=-1|OwnerPartId=-1|Color=8388608|FontID=1|IsHidden=T|Text=2D|Name=Available Preview Images
|RECORD=45|OwnerIndex=689|IndexInSheet=-1|Description=Chip Resistor, 2-Leads, Body 3.10x1.60mm, IPC High Density|UseComponentLibrary=T|ModelName=RESC3116X65X50LL20T20|ModelType=PCBLIB|DatafileCount=1|ModelDatafileEntity0=RESC3116X65X50LL20T20|ModelDatafileKind0=PCBLib|DatalinksLocked=T|DatabaseDatalinksLocked=T
|RECORD=46|OwnerIndex=694
|RECORD=48|OwnerIndex=694
|RECORD=41|OwnerIndex=696|IndexInSheet=-1|OwnerPartId=-1|Color=8388608|FontID=1|IsHidden=T|Text=2D|Name=Available Preview Images
|RECORD=45|OwnerIndex=689|IndexInSheet=-1|Description=Chip Resistor, 2-Leads, Body 3.10x1.60mm, IPC Medium Density|UseComponentLibrary=T|ModelName=RESC3116X65X50NL20T20|ModelType=PCBLIB|DatafileCount=1|ModelDatafileEntity0=RESC3116X65X50NL20T20|ModelDatafileKind0=PCBLib|DatalinksLocked=T|DatabaseDatalinksLocked=T
|RECORD=46|OwnerIndex=698
|RECORD=48|OwnerIndex=698
|RECORD=41|OwnerIndex=700|IndexInSheet=-1|OwnerPartId=-1|Color=8388608|FontID=1|IsHidden=T|Text=2D|Name=Available Preview Images
|RECORD=1|LibReference=RES|PartCount=2|DisplayModeCount=2|IndexInSheet=105|OwnerPartId=-1|Location.X=1350|Location.Y=910|CurrentPartId=1|SourceLibraryName=Altium Content Vault|TargetFileName=*|AreaColor=11599871|Color=128|PartIDLocked=F|DesignItemId=CMP-2003-04873-1|AllPinCount=2|ComponentKindVersion2=5
|RECORD=2|OwnerIndex=702|OwnerPartId=1|OwnerPartDisplayMode=1|FormalType=1|Electrical=4|PinConglomerate=32|PinLength=10|Location.X=1370|Location.Y=900|Name=2|Designator=2|PinPropagationDelay=0.000000E+000
|RECORD=2|OwnerIndex=702|OwnerPartId=1|OwnerPartDisplayMode=1|FormalType=1|Electrical=4|PinConglomerate=34|PinLength=10|Location.X=1350|Location.Y=900|Name=1|Designator=1|PinPropagationDelay=0.000000E+000
|RECORD=14|OwnerIndex=702|IsNotAccesible=T|IndexInSheet=2|OwnerPartId=1|OwnerPartDisplayMode=1|Location.X=1350|Location.Y=896|Corner.X=1370|Corner.Y=904|LineWidth=1|Color=16711680|AreaColor=11599871
|RECORD=2|OwnerIndex=702|OwnerPartId=1|FormalType=1|Electrical=4|PinConglomerate=32|PinLength=10|Location.X=1370|Location.Y=900|Name=2|Designator=2|PinPropagationDelay=0.000000E+000
|RECORD=2|OwnerIndex=702|OwnerPartId=1|FormalType=1|Electrical=4|PinConglomerate=34|PinLength=10|Location.X=1350|Location.Y=900|Name=1|Designator=1|PinPropagationDelay=0.000000E+000
|RECORD=6|OwnerIndex=702|IsNotAccesible=T|IndexInSheet=5|OwnerPartId=1|LineWidth=1|Color=16711680|LocationCount=10|X1=1370|Y1=900|X2=1366|Y2=900|X3=1365|Y3=898|X4=1363|Y4=902|X5=1361|Y5=898|X6=1359|Y6=902|X7=1357|Y7=898|X8=1355|Y8=902|X9=1354|Y9=900|X10=1350|Y10=900
|RECORD=41|OwnerIndex=702|IndexInSheet=6|OwnerPartId=-1|Location.X=1338|Location.Y=913|Color=8388608|FontID=1|IsHidden=T|Text=CRCW12060000Z0EAHP|Name=Part Number
|RECORD=41|OwnerIndex=702|IndexInSheet=7|OwnerPartId=-1|Location.X=1338|Location.Y=913|Color=8388608|FontID=1|IsHidden=T|Text=Vishay Dale|Name=Manufacturer
|RECORD=34|OwnerIndex=702|IndexInSheet=-1|OwnerPartId=-1|Location.X=1349|Location.Y=903|Color=8388608|FontID=1|Text=R46|Name=Designator|ReadOnlyState=1
|RECORD=41|OwnerIndex=702|IndexInSheet=-1|OwnerPartId=-1|Location.X=1349|Location.Y=887|Color=8388608|FontID=1|Text=DNI_0_5%_1206|Name=Comment
|RECORD=44|OwnerIndex=702
|RECORD=45|OwnerIndex=717|IndexInSheet=-1|Description=Chip Resistor, 2-Leads, Body 3.10x1.60mm, IPC Low Density|UseComponentLibrary=T|ModelName=RESC3116X65X50ML20T20|ModelType=PCBLIB|DatafileCount=1|ModelDatafileEntity0=RESC3116X65X50ML20T20|ModelDatafileKind0=PCBLib|IsCurrent=T|DatalinksLocked=T|DatabaseDatalinksLocked=T
|RECORD=46|OwnerIndex=718
|RECORD=48|OwnerIndex=718
|RECORD=41|OwnerIndex=720|IndexInSheet=-1|OwnerPartId=-1|Color=8388608|FontID=1|IsHidden=T|Text=2D|Name=Available Preview Images
|RECORD=45|OwnerIndex=717|IndexInSheet=-1|Description=Chip Resistor, 2-Leads, Body 3.10x1.60mm, IPC High Density|UseComponentLibrary=T|ModelName=RESC3116X65X50LL20T20|ModelType=PCBLIB|DatafileCount=1|ModelDatafileEntity0=RESC3116X65X50LL20T20|ModelDatafileKind0=PCBLib|DatalinksLocked=T|DatabaseDatalinksLocked=T
|RECORD=46|OwnerIndex=722
|RECORD=48|OwnerIndex=722
|RECORD=41|OwnerIndex=724|IndexInSheet=-1|OwnerPartId=-1|Color=8388608|FontID=1|IsHidden=T|Text=2D|Name=Available Preview Images
|RECORD=45|OwnerIndex=717|IndexInSheet=-1|Description=Chip Resistor, 2-Leads, Body 3.10x1.60mm, IPC Medium Density|UseComponentLibrary=T|ModelName=RESC3116X65X50NL20T20|ModelType=PCBLIB|DatafileCount=1|ModelDatafileEntity0=RESC3116X65X50NL20T20|ModelDatafileKind0=PCBLib|DatalinksLocked=T|DatabaseDatalinksLocked=T
|RECORD=46|OwnerIndex=726
|RECORD=48|OwnerIndex=726
|RECORD=41|OwnerIndex=728|IndexInSheet=-1|OwnerPartId=-1|Color=8388608|FontID=1|IsHidden=T|Text=2D|Name=Available Preview Images
|RECORD=17|IndexInSheet=106|OwnerPartId=-1|ShowNetName=T|Location.X=1410|Location.Y=980|Orientation=1|Color=128|FontID=1|Text=+5.0V
|RECORD=17|IndexInSheet=107|OwnerPartId=-1|ShowNetName=T|Location.X=1460|Location.Y=980|Orientation=1|Color=128|FontID=1|Text=+12V
|RECORD=4|IndexInSheet=108|OwnerPartId=-1|Location.X=1360|Location.Y=820|Color=8388608|FontID=1|Text=12V and 3.3V Option for different Atomic clocks
|RECORD=25|IndexInSheet=109|OwnerPartId=-1|Location.X=1070|Location.Y=900|Color=128|FontID=1|Text=MAC_VCC
|RECORD=1|LibReference=RES|PartCount=2|DisplayModeCount=2|IndexInSheet=110|OwnerPartId=-1|Location.X=1350|Location.Y=880|CurrentPartId=1|SourceLibraryName=Altium Content Vault|TargetFileName=*|AreaColor=11599871|Color=128|PartIDLocked=F|DesignItemId=CMP-2003-04873-1|AllPinCount=2|ComponentKindVersion2=5
|RECORD=2|OwnerIndex=734|OwnerPartId=1|OwnerPartDisplayMode=1|FormalType=1|Electrical=4|PinConglomerate=32|PinLength=10|Location.X=1370|Location.Y=870|Name=2|Designator=2|PinPropagationDelay=0.000000E+000
|RECORD=2|OwnerIndex=734|OwnerPartId=1|OwnerPartDisplayMode=1|FormalType=1|Electrical=4|PinConglomerate=34|PinLength=10|Location.X=1350|Location.Y=870|Name=1|Designator=1|PinPropagationDelay=0.000000E+000
|RECORD=14|OwnerIndex=734|IsNotAccesible=T|IndexInSheet=2|OwnerPartId=1|OwnerPartDisplayMode=1|Location.X=1350|Location.Y=866|Corner.X=1370|Corner.Y=874|LineWidth=1|Color=16711680|AreaColor=11599871
|RECORD=2|OwnerIndex=734|OwnerPartId=1|FormalType=1|Electrical=4|PinConglomerate=32|PinLength=10|Location.X=1370|Location.Y=870|Name=2|Designator=2|PinPropagationDelay=0.000000E+000
|RECORD=2|OwnerIndex=734|OwnerPartId=1|FormalType=1|Electrical=4|PinConglomerate=34|PinLength=10|Location.X=1350|Location.Y=870|Name=1|Designator=1|PinPropagationDelay=0.000000E+000
|RECORD=6|OwnerIndex=734|IsNotAccesible=T|IndexInSheet=5|OwnerPartId=1|LineWidth=1|Color=16711680|LocationCount=10|X1=1370|Y1=870|X2=1366|Y2=870|X3=1365|Y3=868|X4=1363|Y4=872|X5=1361|Y5=868|X6=1359|Y6=872|X7=1357|Y7=868|X8=1355|Y8=872|X9=1354|Y9=870|X10=1350|Y10=870
|RECORD=41|OwnerIndex=734|IndexInSheet=6|OwnerPartId=-1|Location.X=1338|Location.Y=883|Color=8388608|FontID=1|IsHidden=T|Text=CRCW12060000Z0EAHP|Name=Part Number
|RECORD=41|OwnerIndex=734|IndexInSheet=7|OwnerPartId=-1|Location.X=1338|Location.Y=883|Color=8388608|FontID=1|IsHidden=T|Text=Vishay Dale|Name=Manufacturer
|RECORD=34|OwnerIndex=734|IndexInSheet=-1|OwnerPartId=-1|Location.X=1349|Location.Y=873|Color=8388608|FontID=1|Text=R47|Name=Designator|ReadOnlyState=1
|RECORD=41|OwnerIndex=734|IndexInSheet=-1|OwnerPartId=-1|Location.X=1349|Location.Y=857|Color=8388608|FontID=1|Text=DNI_0_5%_1206|Name=Comment
|RECORD=44|OwnerIndex=734
|RECORD=45|OwnerIndex=749|IndexInSheet=-1|Description=Chip Resistor, 2-Leads, Body 3.10x1.60mm, IPC Low Density|UseComponentLibrary=T|ModelName=RESC3116X65X50ML20T20|ModelType=PCBLIB|DatafileCount=1|ModelDatafileEntity0=RESC3116X65X50ML20T20|ModelDatafileKind0=PCBLib|IsCurrent=T|DatalinksLocked=T|DatabaseDatalinksLocked=T
|RECORD=46|OwnerIndex=750
|RECORD=48|OwnerIndex=750
|RECORD=41|OwnerIndex=752|IndexInSheet=-1|OwnerPartId=-1|Color=8388608|FontID=1|IsHidden=T|Text=2D|Name=Available Preview Images
|RECORD=45|OwnerIndex=749|IndexInSheet=-1|Description=Chip Resistor, 2-Leads, Body 3.10x1.60mm, IPC High Density|UseComponentLibrary=T|ModelName=RESC3116X65X50LL20T20|ModelType=PCBLIB|DatafileCount=1|ModelDatafileEntity0=RESC3116X65X50LL20T20|ModelDatafileKind0=PCBLib|DatalinksLocked=T|DatabaseDatalinksLocked=T
|RECORD=46|OwnerIndex=754
|RECORD=48|OwnerIndex=754
|RECORD=41|OwnerIndex=756|IndexInSheet=-1|OwnerPartId=-1|Color=8388608|FontID=1|IsHidden=T|Text=2D|Name=Available Preview Images
|RECORD=45|OwnerIndex=749|IndexInSheet=-1|Description=Chip Resistor, 2-Leads, Body 3.10x1.60mm, IPC Medium Density|UseComponentLibrary=T|ModelName=RESC3116X65X50NL20T20|ModelType=PCBLIB|DatafileCount=1|ModelDatafileEntity0=RESC3116X65X50NL20T20|ModelDatafileKind0=PCBLib|DatalinksLocked=T|DatabaseDatalinksLocked=T
|RECORD=46|OwnerIndex=758
|RECORD=48|OwnerIndex=758
|RECORD=41|OwnerIndex=760|IndexInSheet=-1|OwnerPartId=-1|Color=8388608|FontID=1|IsHidden=T|Text=2D|Name=Available Preview Images
|RECORD=17|IndexInSheet=111|OwnerPartId=-1|ShowNetName=T|Location.X=1500|Location.Y=980|Orientation=1|Color=128|FontID=1|Text=+3.3V
|RECORD=1|LibReference=0332-0-43-80-18-27-10-0|ComponentDescription=Solder socket for pin headers|PartCount=2|DisplayModeCount=1|IndexInSheet=112|OwnerPartId=-1|Location.X=540|Location.Y=1020|CurrentPartId=1|LibraryPath=*|SourceLibraryName=FPGA_CONN.SchLib|TargetFileName=*|AreaColor=11599871|Color=128|PartIDLocked=T|DesignItemId=0332-0-43-80-18-27-10-0|AllPinCount=1
|RECORD=12|OwnerIndex=763|IsNotAccesible=T|OwnerPartId=1|Location.X=540|Location.Y=1020|Radius=9|Radius_Frac=71398|LineWidth=1|EndAngle=360.000|Color=16711680
|RECORD=2|OwnerIndex=763|OwnerPartId=1|FormalType=1|Electrical=4|PinConglomerate=48|PinLength=20|Location.X=550|Location.Y=1020|Name=1|Designator=1|SwapIDPart=Ž&Ž||PinPropagationDelay=0.000000E+000
|RECORD=34|OwnerIndex=763|IndexInSheet=-1|OwnerPartId=-1|Location.X=530|Location.X_Frac=28602|Location.Y=1029|Location.Y_Frac=71398|Color=8388608|FontID=1|Text=SKT2|Name=Designator|ReadOnlyState=1
|RECORD=41|OwnerIndex=763|IndexInSheet=-1|OwnerPartId=-1|Location.X=530|Location.X_Frac=28602|Location.Y=1000|Location.Y_Frac=28602|Color=8388608|FontID=1|Text=0332-0-43-80-18-27-10-0|Name=Comment
|RECORD=44|OwnerIndex=763
|RECORD=45|OwnerIndex=769|IndexInSheet=-1|ModelName=SolderSocket|ModelType=PCBLIB|DatafileCount=1|ModelDatafileEntity0=SolderSocket|ModelDatafileKind0=PCBLib|IsCurrent=T
|RECORD=46|OwnerIndex=770
|RECORD=48|OwnerIndex=770
|RECORD=1|LibReference=0332-0-43-80-18-27-10-0|ComponentDescription=Solder socket for pin headers|PartCount=2|DisplayModeCount=1|IndexInSheet=113|OwnerPartId=-1|Location.X=540|Location.Y=980|CurrentPartId=1|LibraryPath=*|SourceLibraryName=FPGA_CONN.SchLib|TargetFileName=*|AreaColor=11599871|Color=128|PartIDLocked=T|DesignItemId=0332-0-43-80-18-27-10-0|AllPinCount=1
|RECORD=12|OwnerIndex=773|IsNotAccesible=T|OwnerPartId=1|Location.X=540|Location.Y=980|Radius=9|Radius_Frac=71398|LineWidth=1|EndAngle=360.000|Color=16711680
|RECORD=2|OwnerIndex=773|OwnerPartId=1|FormalType=1|Electrical=4|PinConglomerate=48|PinLength=20|Location.X=550|Location.Y=980|Name=1|Designator=1|SwapIDPart=Ž&Ž||PinPropagationDelay=0.000000E+000
|RECORD=34|OwnerIndex=773|IndexInSheet=-1|OwnerPartId=-1|Location.X=530|Location.X_Frac=28602|Location.Y=989|Location.Y_Frac=71398|Color=8388608|FontID=1|Text=SKT5|Name=Designator|ReadOnlyState=1
|RECORD=41|OwnerIndex=773|IndexInSheet=-1|OwnerPartId=-1|Location.X=530|Location.X_Frac=28602|Location.Y=960|Location.Y_Frac=28602|Color=8388608|FontID=1|Text=0332-0-43-80-18-27-10-0|Name=Comment
|RECORD=44|OwnerIndex=773
|RECORD=45|OwnerIndex=779|IndexInSheet=-1|ModelName=SolderSocket|ModelType=PCBLIB|DatafileCount=1|ModelDatafileEntity0=SolderSocket|ModelDatafileKind0=PCBLib|IsCurrent=T
|RECORD=46|OwnerIndex=780
|RECORD=48|OwnerIndex=780
|RECORD=1|LibReference=0332-0-43-80-18-27-10-0|ComponentDescription=Solder socket for pin headers|PartCount=2|DisplayModeCount=1|IndexInSheet=114|OwnerPartId=-1|Location.X=540|Location.Y=870|CurrentPartId=1|LibraryPath=*|SourceLibraryName=FPGA_CONN.SchLib|TargetFileName=*|AreaColor=11599871|Color=128|PartIDLocked=T|DesignItemId=0332-0-43-80-18-27-10-0|AllPinCount=1
|RECORD=12|OwnerIndex=783|IsNotAccesible=T|OwnerPartId=1|Location.X=540|Location.Y=870|Radius=9|Radius_Frac=71398|LineWidth=1|EndAngle=360.000|Color=16711680
|RECORD=2|OwnerIndex=783|OwnerPartId=1|FormalType=1|Electrical=4|PinConglomerate=48|PinLength=20|Location.X=550|Location.Y=870|Name=1|Designator=1|SwapIDPart=Ž&Ž||PinPropagationDelay=0.000000E+000
|RECORD=34|OwnerIndex=783|IndexInSheet=-1|OwnerPartId=-1|Location.X=530|Location.X_Frac=28602|Location.Y=879|Location.Y_Frac=71398|Color=8388608|FontID=1|Text=SKT6|Name=Designator|ReadOnlyState=1
|RECORD=41|OwnerIndex=783|IndexInSheet=-1|OwnerPartId=-1|Location.X=530|Location.X_Frac=28602|Location.Y=850|Location.Y_Frac=28602|Color=8388608|FontID=1|Text=0332-0-43-80-18-27-10-0|Name=Comment
|RECORD=44|OwnerIndex=783
|RECORD=45|OwnerIndex=789|IndexInSheet=-1|ModelName=SolderSocket|ModelType=PCBLIB|DatafileCount=1|ModelDatafileEntity0=SolderSocket|ModelDatafileKind0=PCBLib|IsCurrent=T
|RECORD=46|OwnerIndex=790
|RECORD=48|OwnerIndex=790
|RECORD=1|LibReference=0332-0-43-80-18-27-10-0|ComponentDescription=Solder socket for pin headers|PartCount=2|DisplayModeCount=1|IndexInSheet=115|OwnerPartId=-1|Location.X=540|Location.Y=830|CurrentPartId=1|LibraryPath=*|SourceLibraryName=FPGA_CONN.SchLib|TargetFileName=*|AreaColor=11599871|Color=128|PartIDLocked=T|DesignItemId=0332-0-43-80-18-27-10-0|AllPinCount=1
|RECORD=12|OwnerIndex=793|IsNotAccesible=T|OwnerPartId=1|Location.X=540|Location.Y=830|Radius=9|Radius_Frac=71398|LineWidth=1|EndAngle=360.000|Color=16711680
|RECORD=2|OwnerIndex=793|OwnerPartId=1|FormalType=1|Electrical=4|PinConglomerate=48|PinLength=20|Location.X=550|Location.Y=830|Name=1|Designator=1|SwapIDPart=Ž&Ž||PinPropagationDelay=0.000000E+000
|RECORD=34|OwnerIndex=793|IndexInSheet=-1|OwnerPartId=-1|Location.X=530|Location.X_Frac=28602|Location.Y=839|Location.Y_Frac=71398|Color=8388608|FontID=1|Text=SKT9|Name=Designator|ReadOnlyState=1
|RECORD=41|OwnerIndex=793|IndexInSheet=-1|OwnerPartId=-1|Location.X=530|Location.X_Frac=28602|Location.Y=810|Location.Y_Frac=28602|Color=8388608|FontID=1|Text=0332-0-43-80-18-27-10-0|Name=Comment
|RECORD=44|OwnerIndex=793
|RECORD=45|OwnerIndex=799|IndexInSheet=-1|ModelName=SolderSocket|ModelType=PCBLIB|DatafileCount=1|ModelDatafileEntity0=SolderSocket|ModelDatafileKind0=PCBLib|IsCurrent=T
|RECORD=46|OwnerIndex=800
|RECORD=48|OwnerIndex=800
|RECORD=1|LibReference=0332-0-43-80-18-27-10-0|ComponentDescription=Solder socket for pin headers|PartCount=2|DisplayModeCount=1|IndexInSheet=116|OwnerPartId=-1|Location.X=980|Location.Y=1060|Orientation=2|CurrentPartId=1|LibraryPath=*|SourceLibraryName=FPGA_CONN.SchLib|TargetFileName=*|AreaColor=11599871|Color=128|PartIDLocked=T|DesignItemId=0332-0-43-80-18-27-10-0|AllPinCount=1
|RECORD=12|OwnerIndex=803|IsNotAccesible=T|OwnerPartId=1|Location.X=980|Location.Y=1060|Radius=9|Radius_Frac=71398|LineWidth=1|EndAngle=360.000|Color=16711680
|RECORD=2|OwnerIndex=803|OwnerPartId=1|FormalType=1|Electrical=4|PinConglomerate=50|PinLength=20|Location.X=970|Location.Y=1060|Name=1|Designator=1|SwapIDPart=Ž&Ž||PinPropagationDelay=0.000000E+000
|RECORD=34|OwnerIndex=803|IndexInSheet=-1|OwnerPartId=-1|Location.X=970|Location.X_Frac=28602|Location.Y=1069|Location.Y_Frac=71398|Color=8388608|FontID=1|Text=SKT1|Name=Designator|ReadOnlyState=1
|RECORD=41|OwnerIndex=803|IndexInSheet=-1|OwnerPartId=-1|Location.X=970|Location.X_Frac=28602|Location.Y=1040|Location.Y_Frac=28602|Color=8388608|FontID=1|Text=0332-0-43-80-18-27-10-0|Name=Comment
|RECORD=44|OwnerIndex=803
|RECORD=45|OwnerIndex=809|IndexInSheet=-1|ModelName=SolderSocket|ModelType=PCBLIB|DatafileCount=1|ModelDatafileEntity0=SolderSocket|ModelDatafileKind0=PCBLib|IsCurrent=T
|RECORD=46|OwnerIndex=810
|RECORD=48|OwnerIndex=810
|RECORD=1|LibReference=0332-0-43-80-18-27-10-0|ComponentDescription=Solder socket for pin headers|PartCount=2|DisplayModeCount=1|IndexInSheet=117|OwnerPartId=-1|Location.X=980|Location.Y=1020|Orientation=2|CurrentPartId=1|LibraryPath=*|SourceLibraryName=FPGA_CONN.SchLib|TargetFileName=*|AreaColor=11599871|Color=128|PartIDLocked=T|DesignItemId=0332-0-43-80-18-27-10-0|AllPinCount=1
|RECORD=12|OwnerIndex=813|IsNotAccesible=T|OwnerPartId=1|Location.X=980|Location.Y=1020|Radius=9|Radius_Frac=71398|LineWidth=1|EndAngle=360.000|Color=16711680
|RECORD=2|OwnerIndex=813|OwnerPartId=1|FormalType=1|Electrical=4|PinConglomerate=50|PinLength=20|Location.X=970|Location.Y=1020|Name=1|Designator=1|SwapIDPart=Ž&Ž||PinPropagationDelay=0.000000E+000
|RECORD=34|OwnerIndex=813|IndexInSheet=-1|OwnerPartId=-1|Location.X=970|Location.X_Frac=28602|Location.Y=1029|Location.Y_Frac=71398|Color=8388608|FontID=1|Text=SKT3|Name=Designator|ReadOnlyState=1
|RECORD=41|OwnerIndex=813|IndexInSheet=-1|OwnerPartId=-1|Location.X=970|Location.X_Frac=28602|Location.Y=1000|Location.Y_Frac=28602|Color=8388608|FontID=1|Text=0332-0-43-80-18-27-10-0|Name=Comment
|RECORD=44|OwnerIndex=813
|RECORD=45|OwnerIndex=819|IndexInSheet=-1|ModelName=SolderSocket|ModelType=PCBLIB|DatafileCount=1|ModelDatafileEntity0=SolderSocket|ModelDatafileKind0=PCBLib|IsCurrent=T
|RECORD=46|OwnerIndex=820
|RECORD=48|OwnerIndex=820
|RECORD=1|LibReference=0332-0-43-80-18-27-10-0|ComponentDescription=Solder socket for pin headers|PartCount=2|DisplayModeCount=1|IndexInSheet=118|OwnerPartId=-1|Location.X=980|Location.Y=980|Orientation=2|CurrentPartId=1|LibraryPath=*|SourceLibraryName=FPGA_CONN.SchLib|TargetFileName=*|AreaColor=11599871|Color=128|PartIDLocked=T|DesignItemId=0332-0-43-80-18-27-10-0|AllPinCount=1
|RECORD=12|OwnerIndex=823|IsNotAccesible=T|OwnerPartId=1|Location.X=980|Location.Y=980|Radius=9|Radius_Frac=71398|LineWidth=1|EndAngle=360.000|Color=16711680
|RECORD=2|OwnerIndex=823|OwnerPartId=1|FormalType=1|Electrical=4|PinConglomerate=50|PinLength=20|Location.X=970|Location.Y=980|Name=1|Designator=1|SwapIDPart=Ž&Ž||PinPropagationDelay=0.000000E+000
|RECORD=34|OwnerIndex=823|IndexInSheet=-1|OwnerPartId=-1|Location.X=970|Location.X_Frac=28602|Location.Y=989|Location.Y_Frac=71398|Color=8388608|FontID=1|Text=SKT4|Name=Designator|ReadOnlyState=1
|RECORD=41|OwnerIndex=823|IndexInSheet=-1|OwnerPartId=-1|Location.X=970|Location.X_Frac=28602|Location.Y=960|Location.Y_Frac=28602|Color=8388608|FontID=1|Text=0332-0-43-80-18-27-10-0|Name=Comment
|RECORD=44|OwnerIndex=823
|RECORD=45|OwnerIndex=829|IndexInSheet=-1|ModelName=SolderSocket|ModelType=PCBLIB|DatafileCount=1|ModelDatafileEntity0=SolderSocket|ModelDatafileKind0=PCBLib|IsCurrent=T
|RECORD=46|OwnerIndex=830
|RECORD=48|OwnerIndex=830
|RECORD=1|LibReference=0332-0-43-80-18-27-10-0|ComponentDescription=Solder socket for pin headers|PartCount=2|DisplayModeCount=1|IndexInSheet=119|OwnerPartId=-1|Location.X=1090|Location.Y=870|Orientation=2|CurrentPartId=1|LibraryPath=*|SourceLibraryName=FPGA_CONN.SchLib|TargetFileName=*|AreaColor=11599871|Color=128|PartIDLocked=T|DesignItemId=0332-0-43-80-18-27-10-0|AllPinCount=1
|RECORD=12|OwnerIndex=833|IsNotAccesible=T|OwnerPartId=1|Location.X=1090|Location.Y=870|Radius=9|Radius_Frac=71398|LineWidth=1|EndAngle=360.000|Color=16711680
|RECORD=2|OwnerIndex=833|OwnerPartId=1|FormalType=1|Electrical=4|PinConglomerate=50|PinLength=20|Location.X=1080|Location.Y=870|Name=1|Designator=1|SwapIDPart=Ž&Ž||PinPropagationDelay=0.000000E+000
|RECORD=34|OwnerIndex=833|IndexInSheet=-1|OwnerPartId=-1|Location.X=1080|Location.X_Frac=28602|Location.Y=879|Location.Y_Frac=71398|Color=8388608|FontID=1|Text=SKT7|Name=Designator|ReadOnlyState=1
|RECORD=41|OwnerIndex=833|IndexInSheet=-1|OwnerPartId=-1|Location.X=1080|Location.X_Frac=28602|Location.Y=850|Location.Y_Frac=28602|Color=8388608|FontID=1|Text=0332-0-43-80-18-27-10-0|Name=Comment
|RECORD=44|OwnerIndex=833
|RECORD=45|OwnerIndex=839|IndexInSheet=-1|ModelName=SolderSocket|ModelType=PCBLIB|DatafileCount=1|ModelDatafileEntity0=SolderSocket|ModelDatafileKind0=PCBLib|IsCurrent=T
|RECORD=46|OwnerIndex=840
|RECORD=48|OwnerIndex=840
|RECORD=1|LibReference=0332-0-43-80-18-27-10-0|ComponentDescription=Solder socket for pin headers|PartCount=2|DisplayModeCount=1|IndexInSheet=120|OwnerPartId=-1|Location.X=960|Location.Y=850|Orientation=2|CurrentPartId=1|LibraryPath=*|SourceLibraryName=FPGA_CONN.SchLib|TargetFileName=*|AreaColor=11599871|Color=128|PartIDLocked=T|DesignItemId=0332-0-43-80-18-27-10-0|AllPinCount=1
|RECORD=12|OwnerIndex=843|IsNotAccesible=T|OwnerPartId=1|Location.X=960|Location.Y=850|Radius=9|Radius_Frac=71398|LineWidth=1|EndAngle=360.000|Color=16711680
|RECORD=2|OwnerIndex=843|OwnerPartId=1|FormalType=1|Electrical=4|PinConglomerate=50|PinLength=20|Location.X=950|Location.Y=850|Name=1|Designator=1|SwapIDPart=Ž&Ž||PinPropagationDelay=0.000000E+000
|RECORD=34|OwnerIndex=843|IndexInSheet=-1|OwnerPartId=-1|Location.X=950|Location.X_Frac=28602|Location.Y=859|Location.Y_Frac=71398|Color=8388608|FontID=1|Text=SKT8|Name=Designator|ReadOnlyState=1
|RECORD=41|OwnerIndex=843|IndexInSheet=-1|OwnerPartId=-1|Location.X=950|Location.X_Frac=28602|Location.Y=830|Location.Y_Frac=28602|Color=8388608|FontID=1|Text=0332-0-43-80-18-27-10-0|Name=Comment
|RECORD=44|OwnerIndex=843
|RECORD=45|OwnerIndex=849|IndexInSheet=-1|ModelName=SolderSocket|ModelType=PCBLIB|DatafileCount=1|ModelDatafileEntity0=SolderSocket|ModelDatafileKind0=PCBLib|IsCurrent=T
|RECORD=46|OwnerIndex=850
|RECORD=48|OwnerIndex=850
|RECORD=1|LibReference=0332-0-43-80-18-27-10-0|ComponentDescription=Solder socket for pin headers|PartCount=2|DisplayModeCount=1|IndexInSheet=121|OwnerPartId=-1|Location.X=960|Location.Y=810|Orientation=2|CurrentPartId=1|LibraryPath=*|SourceLibraryName=FPGA_CONN.SchLib|TargetFileName=*|AreaColor=11599871|Color=128|PartIDLocked=T|DesignItemId=0332-0-43-80-18-27-10-0|AllPinCount=1
|RECORD=12|OwnerIndex=853|IsNotAccesible=T|OwnerPartId=1|Location.X=960|Location.Y=810|Radius=9|Radius_Frac=71398|LineWidth=1|EndAngle=360.000|Color=16711680
|RECORD=2|OwnerIndex=853|OwnerPartId=1|FormalType=1|Electrical=4|PinConglomerate=50|PinLength=20|Location.X=950|Location.Y=810|Name=1|Designator=1|SwapIDPart=Ž&Ž||PinPropagationDelay=0.000000E+000
|RECORD=34|OwnerIndex=853|IndexInSheet=-1|OwnerPartId=-1|Location.X=950|Location.X_Frac=28602|Location.Y=819|Location.Y_Frac=71398|Color=8388608|FontID=1|Text=SKT10|Name=Designator|ReadOnlyState=1
|RECORD=41|OwnerIndex=853|IndexInSheet=-1|OwnerPartId=-1|Location.X=950|Location.X_Frac=28602|Location.Y=790|Location.Y_Frac=28602|Color=8388608|FontID=1|Text=0332-0-43-80-18-27-10-0|Name=Comment
|RECORD=44|OwnerIndex=853
|RECORD=45|OwnerIndex=859|IndexInSheet=-1|ModelName=SolderSocket|ModelType=PCBLIB|DatafileCount=1|ModelDatafileEntity0=SolderSocket|ModelDatafileKind0=PCBLib|IsCurrent=T
|RECORD=46|OwnerIndex=860
|RECORD=48|OwnerIndex=860
|RECORD=27|IndexInSheet=122|OwnerPartId=-1|LineWidth=1|Color=8388608|LocationCount=2|Y1=1100|X2=100|Y2=1100
|RECORD=27|IndexInSheet=123|OwnerPartId=-1|LineWidth=1|Color=8388608|LocationCount=3|X1=618|Y1=917|X2=640|Y2=917|X3=668|Y3=917
|RECORD=27|IndexInSheet=124|OwnerPartId=-1|LineWidth=1|Color=8388608|LocationCount=3|X1=618|Y1=937|X2=630|Y2=937|X3=668|Y3=937
|RECORD=27|IndexInSheet=125|OwnerPartId=-1|LineWidth=1|Color=8388608|LocationCount=2|X1=668|Y1=907|X2=648|Y2=907
|RECORD=27|IndexInSheet=126|OwnerPartId=-1|LineWidth=1|Color=8388608|LocationCount=2|X1=790|Y1=550|X2=810|Y2=550
|RECORD=27|IndexInSheet=127|OwnerPartId=-1|LineWidth=1|Color=8388608|LocationCount=2|X1=790|Y1=560|X2=810|Y2=560
|RECORD=27|IndexInSheet=128|OwnerPartId=-1|LineWidth=1|Color=8388608|LocationCount=3|X1=878|Y1=917|X2=910|Y2=917|X3=918|Y3=917
|RECORD=27|IndexInSheet=129|OwnerPartId=-1|LineWidth=1|Color=8388608|LocationCount=3|X1=878|Y1=927|X2=900|Y2=927|X3=918|Y3=927
|RECORD=27|IndexInSheet=130|OwnerPartId=-1|LineWidth=1|Color=8388608|LocationCount=3|X1=878|Y1=937|X2=890|Y2=937|X3=918|Y3=937
|RECORD=27|IndexInSheet=131|OwnerPartId=-1|LineWidth=1|Color=8388608|LocationCount=4|X1=1240|Y1=870|X2=1240|Y2=856|X3=1181|Y3=856|X4=1181|Y4=866
|RECORD=27|IndexInSheet=132|OwnerPartId=-1|LineWidth=1|Color=8388608|LocationCount=3|X1=970|Y1=260|X2=1040|Y2=260|X3=1110|Y3=260
|RECORD=27|IndexInSheet=133|OwnerPartId=-1|LineWidth=1|Color=8388608|LocationCount=2|X1=1010|Y1=230|X2=1010|Y2=290
|RECORD=27|IndexInSheet=134|OwnerPartId=-1|LineWidth=1|Color=8388608|LocationCount=2|X1=1040|Y1=230|X2=1040|Y2=260
|RECORD=27|IndexInSheet=135|OwnerPartId=-1|LineWidth=1|Color=8388608|LocationCount=3|X1=1110|Y1=290|X2=1010|Y2=290|X3=970|Y3=290
|RECORD=27|IndexInSheet=136|OwnerPartId=-1|LineWidth=1|Color=8388608|LocationCount=2|X1=1010|Y1=170|X2=1010|Y2=190
|RECORD=27|IndexInSheet=137|OwnerPartId=-1|LineWidth=1|Color=8388608|LocationCount=2|X1=1040|Y1=170|X2=1040|Y2=190
|RECORD=27|IndexInSheet=138|OwnerPartId=-1|LineWidth=1|Color=8388608|LocationCount=2|X1=1080|Y1=170|X2=1080|Y2=190
|RECORD=27|IndexInSheet=139|OwnerPartId=-1|LineWidth=1|Color=8388608|LocationCount=3|X1=1080|Y1=220|X2=1080|Y2=230|X3=1110|Y3=230
|RECORD=27|IndexInSheet=140|OwnerPartId=-1|LineWidth=1|Color=8388608|LocationCount=2|X1=1080|Y1=230|X2=1080|Y2=320
|RECORD=27|IndexInSheet=141|OwnerPartId=-1|LineWidth=1|Color=8388608|LocationCount=2|X1=1220|Y1=290|X2=1280|Y2=290
|RECORD=27|IndexInSheet=142|OwnerPartId=-1|LineWidth=1|Color=8388608|LocationCount=2|X1=1220|Y1=280|X2=1280|Y2=280
|RECORD=27|IndexInSheet=143|OwnerPartId=-1|LineWidth=1|Color=8388608|LocationCount=2|X1=1220|Y1=260|X2=1280|Y2=260
|RECORD=27|IndexInSheet=144|OwnerPartId=-1|LineWidth=1|Color=8388608|LocationCount=2|X1=1220|Y1=250|X2=1280|Y2=250
|RECORD=27|IndexInSheet=145|OwnerPartId=-1|LineWidth=1|Color=8388608|LocationCount=3|X1=1220|Y1=230|X2=1260|Y2=230|X3=1260|Y3=170
|RECORD=27|IndexInSheet=146|OwnerPartId=-1|LineWidth=1|Color=8388608|LocationCount=3|X1=190|Y1=310|X2=230|Y2=310|X3=230|Y3=300
|RECORD=27|IndexInSheet=147|OwnerPartId=-1|LineWidth=1|Color=8388608|LocationCount=3|X1=190|Y1=250|X2=230|Y2=250|X3=230|Y3=260
|RECORD=27|IndexInSheet=148|OwnerPartId=-1|LineWidth=1|Color=8388608|LocationCount=4|X1=230|Y1=250|X2=260|Y2=250|X3=260|Y3=260|X4=320|Y4=260
|RECORD=27|IndexInSheet=149|OwnerPartId=-1|LineWidth=1|Color=8388608|LocationCount=4|X1=320|Y1=270|X2=260|Y2=270|X3=260|Y3=310|X4=230|Y4=310
|RECORD=27|IndexInSheet=150|OwnerPartId=-1|LineWidth=1|Color=8388608|LocationCount=3|X1=320|Y1=210|X2=290|Y2=210|X3=290|Y3=190
|RECORD=27|IndexInSheet=151|OwnerPartId=-1|LineWidth=1|Color=8388608|LocationCount=2|X1=290|Y1=210|X2=290|Y2=330
|RECORD=27|IndexInSheet=152|OwnerPartId=-1|LineWidth=1|Color=8388608|LocationCount=3|X1=440|Y1=210|X2=480|Y2=210|X3=480|Y3=130
|RECORD=27|IndexInSheet=153|OwnerPartId=-1|LineWidth=1|Color=8388608|LocationCount=2|X1=290|Y1=130|X2=290|Y2=160
|RECORD=27|IndexInSheet=154|OwnerPartId=-1|LineWidth=1|Color=8388608|LocationCount=3|X1=880|Y1=880|X2=910|Y2=880|X3=940|Y3=880
|RECORD=27|IndexInSheet=155|OwnerPartId=-1|LineWidth=1|Color=8388608|LocationCount=3|X1=940|Y1=890|X2=920|Y2=890|X3=880|Y3=890
|RECORD=27|IndexInSheet=156|OwnerPartId=-1|LineWidth=1|Color=8388608|LocationCount=2|X1=1181|Y1=900|X2=1181|Y2=896
|RECORD=27|IndexInSheet=157|OwnerPartId=-1|LineWidth=1|Color=8388608|LocationCount=3|X1=630|Y1=470|X2=580|Y2=470|X3=580|Y3=660
|RECORD=27|IndexInSheet=158|OwnerPartId=-1|LineWidth=1|Color=8388608|LocationCount=3|X1=630|Y1=460|X2=570|Y2=460|X3=570|Y3=650
|RECORD=27|IndexInSheet=159|OwnerPartId=-1|LineWidth=1|Color=8388608|LocationCount=3|X1=630|Y1=450|X2=560|Y2=450|X3=560|Y3=640
|RECORD=27|IndexInSheet=160|OwnerPartId=-1|LineWidth=1|Color=8388608|LocationCount=3|X1=630|Y1=440|X2=550|Y2=440|X3=550|Y3=630
|RECORD=27|IndexInSheet=161|OwnerPartId=-1|LineWidth=1|Color=8388608|LocationCount=3|X1=790|Y1=470|X2=840|Y2=470|X3=840|Y3=660
|RECORD=27|IndexInSheet=162|OwnerPartId=-1|LineWidth=1|Color=8388608|LocationCount=3|X1=790|Y1=460|X2=850|Y2=460|X3=850|Y3=650
|RECORD=27|IndexInSheet=163|OwnerPartId=-1|LineWidth=1|Color=8388608|LocationCount=3|X1=790|Y1=450|X2=860|Y2=450|X3=860|Y3=640
|RECORD=27|IndexInSheet=164|OwnerPartId=-1|LineWidth=1|Color=8388608|LocationCount=3|X1=790|Y1=430|X2=890|Y2=430|X3=890|Y3=620
|RECORD=27|IndexInSheet=165|OwnerPartId=-1|LineWidth=1|Color=8388608|LocationCount=3|X1=790|Y1=420|X2=900|Y2=420|X3=900|Y3=610
|RECORD=27|IndexInSheet=166|OwnerPartId=-1|LineWidth=1|Color=8388608|LocationCount=3|X1=790|Y1=400|X2=920|Y2=400|X3=920|Y3=590
|RECORD=27|IndexInSheet=167|OwnerPartId=-1|LineWidth=1|Color=8388608|LocationCount=2|X1=790|Y1=360|X2=800|Y2=360
|RECORD=27|IndexInSheet=168|OwnerPartId=-1|LineWidth=1|Color=8388608|LocationCount=2|X1=790|Y1=370|X2=800|Y2=370
|RECORD=27|IndexInSheet=169|OwnerPartId=-1|LineWidth=1|Color=8388608|LocationCount=3|X1=1380|Y1=940|X2=1410|Y2=940|X3=1410|Y3=980
|RECORD=27|IndexInSheet=170|OwnerPartId=-1|LineWidth=1|Color=8388608|LocationCount=4|X1=878|Y1=907|X2=878|Y2=900|X3=1050|Y3=900|X4=1181|Y4=900
|RECORD=27|IndexInSheet=171|OwnerPartId=-1|LineWidth=1|Color=8388608|LocationCount=3|X1=1340|Y1=940|X2=1290|Y2=940|X3=1290|Y3=900
|RECORD=27|IndexInSheet=172|OwnerPartId=-1|LineWidth=1|Color=8388608|LocationCount=3|X1=1380|Y1=900|X2=1460|Y2=900|X3=1460|Y3=980
|RECORD=27|IndexInSheet=173|OwnerPartId=-1|LineWidth=1|Color=8388608|LocationCount=3|X1=1380|Y1=870|X2=1500|Y2=870|X3=1500|Y3=980
|RECORD=27|IndexInSheet=174|OwnerPartId=-1|LineWidth=1|Color=8388608|LocationCount=3|X1=1340|Y1=870|X2=1290|Y2=870|X3=1290|Y3=900
|RECORD=27|IndexInSheet=175|OwnerPartId=-1|LineWidth=1|Color=8388608|LocationCount=3|X1=420|Y1=630|X2=550|Y2=630|X3=610|Y3=630
|RECORD=27|IndexInSheet=176|OwnerPartId=-1|LineWidth=1|Color=8388608|LocationCount=3|X1=610|Y1=640|X2=560|Y2=640|X3=420|Y3=640
|RECORD=27|IndexInSheet=177|OwnerPartId=-1|LineWidth=1|Color=8388608|LocationCount=3|X1=610|Y1=650|X2=570|Y2=650|X3=420|Y3=650
|RECORD=27|IndexInSheet=178|OwnerPartId=-1|LineWidth=1|Color=8388608|LocationCount=3|X1=610|Y1=660|X2=580|Y2=660|X3=420|Y3=660
|RECORD=27|IndexInSheet=179|OwnerPartId=-1|LineWidth=1|Color=8388608|LocationCount=5|X1=790|Y1=380|X2=800|Y2=380|X3=800|Y3=370|X4=800|Y4=360|X5=800|Y5=350
|RECORD=27|IndexInSheet=180|OwnerPartId=-1|LineWidth=1|Color=8388608|LocationCount=5|X1=790|Y1=570|X2=810|Y2=570|X3=810|Y3=560|X4=810|Y4=550|X5=810|Y5=530
|RECORD=27|IndexInSheet=181|OwnerPartId=-1|LineWidth=1|Color=8388608|LocationCount=3|X1=1040|Y1=590|X2=920|Y2=590|X3=790|Y3=590
|RECORD=27|IndexInSheet=182|OwnerPartId=-1|LineWidth=1|Color=8388608|LocationCount=3|X1=1040|Y1=610|X2=900|Y2=610|X3=790|Y3=610
|RECORD=27|IndexInSheet=183|OwnerPartId=-1|LineWidth=1|Color=8388608|LocationCount=3|X1=1040|Y1=620|X2=890|Y2=620|X3=790|Y3=620
|RECORD=27|IndexInSheet=184|OwnerPartId=-1|LineWidth=1|Color=8388608|LocationCount=3|X1=1040|Y1=640|X2=860|Y2=640|X3=790|Y3=640
|RECORD=27|IndexInSheet=185|OwnerPartId=-1|LineWidth=1|Color=8388608|LocationCount=3|X1=1040|Y1=650|X2=850|Y2=650|X3=790|Y3=650
|RECORD=27|IndexInSheet=186|OwnerPartId=-1|LineWidth=1|Color=8388608|LocationCount=3|X1=1040|Y1=660|X2=840|Y2=660|X3=790|Y3=660
|RECORD=27|IndexInSheet=187|OwnerPartId=-1|LineWidth=1|Color=8388608|LocationCount=7|X1=668|Y1=927|X2=648|Y2=927|X3=648|Y3=907|X4=640|Y4=907|X5=640|Y5=870|X6=640|Y6=830|X7=640|Y7=810
|RECORD=27|IndexInSheet=188|OwnerPartId=-1|LineWidth=1|Color=8388608|LocationCount=4|X1=1181|Y1=900|X2=1240|Y2=900|X3=1290|Y3=900|X4=1340|Y4=900
|RECORD=27|IndexInSheet=189|OwnerPartId=-1|LineWidth=1|Color=8388608|LocationCount=3|X1=570|Y1=980|X2=640|Y2=980|X3=640|Y3=917
|RECORD=27|IndexInSheet=190|OwnerPartId=-1|LineWidth=1|Color=8388608|LocationCount=3|X1=570|Y1=1020|X2=630|Y2=1020|X3=630|Y3=937
|RECORD=27|IndexInSheet=191|OwnerPartId=-1|LineWidth=1|Color=8388608|LocationCount=2|X1=570|Y1=870|X2=640|Y2=870
|RECORD=27|IndexInSheet=192|OwnerPartId=-1|LineWidth=1|Color=8388608|LocationCount=2|X1=570|Y1=830|X2=640|Y2=830
|RECORD=27|IndexInSheet=193|OwnerPartId=-1|LineWidth=1|Color=8388608|LocationCount=3|X1=910|Y1=917|X2=910|Y2=980|X3=950|Y3=980
|RECORD=27|IndexInSheet=194|OwnerPartId=-1|LineWidth=1|Color=8388608|LocationCount=3|X1=900|Y1=927|X2=900|Y2=1020|X3=950|Y3=1020
|RECORD=27|IndexInSheet=195|OwnerPartId=-1|LineWidth=1|Color=8388608|LocationCount=3|X1=950|Y1=1060|X2=890|Y2=1060|X3=890|Y3=937
|RECORD=27|IndexInSheet=196|OwnerPartId=-1|LineWidth=1|Color=8388608|LocationCount=3|X1=1060|Y1=870|X2=1050|Y2=870|X3=1050|Y3=900
|RECORD=27|IndexInSheet=197|OwnerPartId=-1|LineWidth=1|Color=8388608|LocationCount=3|X1=930|Y1=850|X2=920|Y2=850|X3=920|Y3=890
|RECORD=27|IndexInSheet=198|OwnerPartId=-1|LineWidth=1|Color=8388608|LocationCount=3|X1=930|Y1=810|X2=910|Y2=810|X3=910|Y3=880
|RECORD=1|LibReference=SA53 Screw|PartCount=2|DisplayModeCount=1|IndexInSheet=199|OwnerPartId=-1|Location.X=1260|Location.Y=720|CurrentPartId=1|LibraryPath=*|SourceLibraryName=FPGA_CONN.SchLib|TargetFileName=*|AreaColor=11599871|Color=128|PartIDLocked=T|DesignItemId=SA53 Screw
|RECORD=41|OwnerIndex=940|OwnerPartId=-1|Location.X=1250|Location.X_Frac=29620|Location.Y=735|Color=8388608|FontID=1|IsHidden=T|Text=Digi-Key|Name=Supplier 1|ReadOnlyState=3
|RECORD=12|OwnerIndex=940|IsNotAccesible=T|IndexInSheet=1|OwnerPartId=1|Location.X=1260|Location.Y=720|Radius=9|Radius_Frac=70380|LineWidth=1|EndAngle=360.000|Color=16711680
|RECORD=41|OwnerIndex=940|IndexInSheet=2|OwnerPartId=-1|Location.X=1250|Location.X_Frac=29620|Location.Y=690|Location.Y_Frac=29620|Color=8388608|FontID=1|Text=H700-ND|Name=Supplier Part Number 1|ReadOnlyState=3
|RECORD=34|OwnerIndex=940|IndexInSheet=-1|OwnerPartId=-1|Location.X=1250|Location.X_Frac=29620|Location.Y=729|Location.Y_Frac=70380|Color=8388608|FontID=1|Text=J39|Name=Designator|ReadOnlyState=1
|RECORD=41|OwnerIndex=940|IndexInSheet=-1|OwnerPartId=-1|Location.X=1250|Location.X_Frac=29620|Location.Y=700|Location.Y_Frac=29620|Color=8388608|FontID=1|Text=SA53 Screw|Name=Comment
|RECORD=44|OwnerIndex=940
|RECORD=1|LibReference=SA53 Screw|PartCount=2|DisplayModeCount=1|IndexInSheet=200|OwnerPartId=-1|Location.X=1260|Location.Y=660|CurrentPartId=1|LibraryPath=*|SourceLibraryName=FPGA_CONN.SchLib|TargetFileName=*|AreaColor=11599871|Color=128|PartIDLocked=T|DesignItemId=SA53 Screw
|RECORD=41|OwnerIndex=947|OwnerPartId=-1|Location.X=1250|Location.X_Frac=29620|Location.Y=675|Color=8388608|FontID=1|IsHidden=T|Text=Digi-Key|Name=Supplier 1|ReadOnlyState=3
|RECORD=12|OwnerIndex=947|IsNotAccesible=T|IndexInSheet=1|OwnerPartId=1|Location.X=1260|Location.Y=660|Radius=9|Radius_Frac=70380|LineWidth=1|EndAngle=360.000|Color=16711680
|RECORD=41|OwnerIndex=947|IndexInSheet=2|OwnerPartId=-1|Location.X=1250|Location.X_Frac=29620|Location.Y=630|Location.Y_Frac=29620|Color=8388608|FontID=1|Text=H700-ND|Name=Supplier Part Number 1|ReadOnlyState=3
|RECORD=34|OwnerIndex=947|IndexInSheet=-1|OwnerPartId=-1|Location.X=1250|Location.X_Frac=29620|Location.Y=669|Location.Y_Frac=70380|Color=8388608|FontID=1|Text=J41|Name=Designator|ReadOnlyState=1
|RECORD=41|OwnerIndex=947|IndexInSheet=-1|OwnerPartId=-1|Location.X=1250|Location.X_Frac=29620|Location.Y=640|Location.Y_Frac=29620|Color=8388608|FontID=1|Text=SA53 Screw|Name=Comment
|RECORD=44|OwnerIndex=947
|RECORD=1|LibReference=SA53 Screw|PartCount=2|DisplayModeCount=1|IndexInSheet=201|OwnerPartId=-1|Location.X=1330|Location.Y=720|CurrentPartId=1|LibraryPath=*|SourceLibraryName=FPGA_CONN.SchLib|TargetFileName=*|AreaColor=11599871|Color=128|PartIDLocked=T|DesignItemId=SA53 Screw
|RECORD=41|OwnerIndex=954|OwnerPartId=-1|Location.X=1320|Location.X_Frac=29620|Location.Y=735|Color=8388608|FontID=1|IsHidden=T|Text=Digi-Key|Name=Supplier 1|ReadOnlyState=3
|RECORD=12|OwnerIndex=954|IsNotAccesible=T|IndexInSheet=1|OwnerPartId=1|Location.X=1330|Location.Y=720|Radius=9|Radius_Frac=70380|LineWidth=1|EndAngle=360.000|Color=16711680
|RECORD=41|OwnerIndex=954|IndexInSheet=2|OwnerPartId=-1|Location.X=1320|Location.X_Frac=29620|Location.Y=690|Location.Y_Frac=29620|Color=8388608|FontID=1|Text=H700-ND|Name=Supplier Part Number 1|ReadOnlyState=3
|RECORD=34|OwnerIndex=954|IndexInSheet=-1|OwnerPartId=-1|Location.X=1320|Location.X_Frac=29620|Location.Y=729|Location.Y_Frac=70380|Color=8388608|FontID=1|Text=J40|Name=Designator|ReadOnlyState=1
|RECORD=41|OwnerIndex=954|IndexInSheet=-1|OwnerPartId=-1|Location.X=1320|Location.X_Frac=29620|Location.Y=700|Location.Y_Frac=29620|Color=8388608|FontID=1|Text=SA53 Screw|Name=Comment
|RECORD=44|OwnerIndex=954
|RECORD=1|LibReference=SA53 Screw|PartCount=2|DisplayModeCount=1|IndexInSheet=202|OwnerPartId=-1|Location.X=1330|Location.Y=660|CurrentPartId=1|LibraryPath=*|SourceLibraryName=FPGA_CONN.SchLib|TargetFileName=*|AreaColor=11599871|Color=128|PartIDLocked=T|DesignItemId=SA53 Screw
|RECORD=41|OwnerIndex=961|OwnerPartId=-1|Location.X=1320|Location.X_Frac=29620|Location.Y=675|Color=8388608|FontID=1|IsHidden=T|Text=Digi-Key|Name=Supplier 1|ReadOnlyState=3
|RECORD=12|OwnerIndex=961|IsNotAccesible=T|IndexInSheet=1|OwnerPartId=1|Location.X=1330|Location.Y=660|Radius=9|Radius_Frac=70380|LineWidth=1|EndAngle=360.000|Color=16711680
|RECORD=41|OwnerIndex=961|IndexInSheet=2|OwnerPartId=-1|Location.X=1320|Location.X_Frac=29620|Location.Y=630|Location.Y_Frac=29620|Color=8388608|FontID=1|Text=H700-ND|Name=Supplier Part Number 1|ReadOnlyState=3
|RECORD=34|OwnerIndex=961|IndexInSheet=-1|OwnerPartId=-1|Location.X=1320|Location.X_Frac=29620|Location.Y=669|Location.Y_Frac=70380|Color=8388608|FontID=1|Text=J42|Name=Designator|ReadOnlyState=1
|RECORD=41|OwnerIndex=961|IndexInSheet=-1|OwnerPartId=-1|Location.X=1320|Location.X_Frac=29620|Location.Y=640|Location.Y_Frac=29620|Color=8388608|FontID=1|Text=SA53 Screw|Name=Comment
|RECORD=44|OwnerIndex=961
|RECORD=27|IndexInSheet=203|OwnerPartId=-1|LineWidth=1|Color=8388608|LocationCount=2|X1=440|Y1=270|X2=580|Y2=270
|RECORD=29|IndexInSheet=-1|OwnerPartId=-1|Location.X=230|Location.Y=250|Color=128
|RECORD=29|IndexInSheet=-1|OwnerPartId=-1|Location.X=230|Location.Y=310|Color=128
|RECORD=29|IndexInSheet=-1|OwnerPartId=-1|Location.X=290|Location.Y=210|Color=128
|RECORD=29|IndexInSheet=-1|OwnerPartId=-1|Location.X=550|Location.Y=630|Color=128
|RECORD=29|IndexInSheet=-1|OwnerPartId=-1|Location.X=560|Location.Y=640|Color=128
|RECORD=29|IndexInSheet=-1|OwnerPartId=-1|Location.X=570|Location.Y=650|Color=128
|RECORD=29|IndexInSheet=-1|OwnerPartId=-1|Location.X=580|Location.Y=660|Color=128
|RECORD=29|IndexInSheet=-1|OwnerPartId=-1|Location.X=630|Location.Y=937|Color=128
|RECORD=29|IndexInSheet=-1|OwnerPartId=-1|Location.X=640|Location.Y=830|Color=128
|RECORD=29|IndexInSheet=-1|OwnerPartId=-1|Location.X=640|Location.Y=870|Color=128
|RECORD=29|IndexInSheet=-1|OwnerPartId=-1|Location.X=640|Location.Y=917|Color=128
|RECORD=29|IndexInSheet=-1|OwnerPartId=-1|Location.X=648|Location.Y=907|Color=128
|RECORD=29|IndexInSheet=-1|OwnerPartId=-1|Location.X=800|Location.Y=360|Color=128
|RECORD=29|IndexInSheet=-1|OwnerPartId=-1|Location.X=800|Location.Y=370|Color=128
|RECORD=29|IndexInSheet=-1|OwnerPartId=-1|Location.X=810|Location.Y=550|Color=128
|RECORD=29|IndexInSheet=-1|OwnerPartId=-1|Location.X=810|Location.Y=560|Color=128
|RECORD=29|IndexInSheet=-1|OwnerPartId=-1|Location.X=840|Location.Y=660|Color=128
|RECORD=29|IndexInSheet=-1|OwnerPartId=-1|Location.X=850|Location.Y=650|Color=128
|RECORD=29|IndexInSheet=-1|OwnerPartId=-1|Location.X=860|Location.Y=640|Color=128
|RECORD=29|IndexInSheet=-1|OwnerPartId=-1|Location.X=890|Location.Y=620|Color=128
|RECORD=29|IndexInSheet=-1|OwnerPartId=-1|Location.X=890|Location.Y=937|Color=128
|RECORD=29|IndexInSheet=-1|OwnerPartId=-1|Location.X=900|Location.Y=610|Color=128
|RECORD=29|IndexInSheet=-1|OwnerPartId=-1|Location.X=900|Location.Y=927|Color=128
|RECORD=29|IndexInSheet=-1|OwnerPartId=-1|Location.X=910|Location.Y=880|Color=128
|RECORD=29|IndexInSheet=-1|OwnerPartId=-1|Location.X=910|Location.Y=917|Color=128
|RECORD=29|IndexInSheet=-1|OwnerPartId=-1|Location.X=920|Location.Y=590|Color=128
|RECORD=29|IndexInSheet=-1|OwnerPartId=-1|Location.X=920|Location.Y=890|Color=128
|RECORD=29|IndexInSheet=-1|OwnerPartId=-1|Location.X=1010|Location.Y=290|Color=128
|RECORD=29|IndexInSheet=-1|OwnerPartId=-1|Location.X=1040|Location.Y=260|Color=128
|RECORD=29|IndexInSheet=-1|OwnerPartId=-1|Location.X=1050|Location.Y=900|Color=128
|RECORD=29|IndexInSheet=-1|OwnerPartId=-1|Location.X=1080|Location.Y=230|Color=128
|RECORD=29|IndexInSheet=-1|OwnerPartId=-1|Location.X=1181|Location.Y=900|Color=128
|RECORD=29|IndexInSheet=-1|OwnerPartId=-1|Location.X=1240|Location.Y=856|Color=128
|RECORD=29|IndexInSheet=-1|OwnerPartId=-1|Location.X=1240|Location.Y=900|Color=128
|RECORD=29|IndexInSheet=-1|OwnerPartId=-1|Location.X=1290|Location.Y=900|Color=128